FILE_TYPE = MACRO_DRAWING;
SET COLOR_WIRE YELLOW;
SET COLOR_PROP ORANGE;
SET COLOR_DOT WHITE;
SET COLOR_ARC YELLOW;
SET COLOR_BODY GREEN;
SET COLOR_NOTE PURPLE;
SET PROP_DISPLAY VALUE;
SET PAGE_NUMBER P44;
FORCEADD GENOA_SP5..8
(-4625 3525);
FORCEPROP 1 LAST LOCATION U26
J 0
(-5270 6356);
DISPLAY 0.489362 (-5270 6356);
PAINT SKYBLUE (-5270 6356);
FORCEPROP 0 LAST $SEC 8
J 0
(-5250 6400);
DISPLAY 0.680851 (-5250 6400);
PAINT MONO (-5250 6400);
DISPLAY INVISIBLE (-5250 6400);
FORCEPROP 0 LAST CDS_SEC 8
J 0
(-5275 6350);
DISPLAY 1.021277 (-5275 6350);
DISPLAY INVISIBLE (-5275 6350);
FORCEPROP 0 LASTPIN (-5425 2900) $PN BC12
J 2
(-5435 2910);
DISPLAY 0.489362 (-5435 2910);
PAINT MONO (-5435 2910);
FORCEPROP 0 LASTPIN (-5425 2850) $PN BD13
J 2
(-5435 2860);
DISPLAY 0.489362 (-5435 2860);
PAINT MONO (-5435 2860);
FORCEPROP 0 LASTPIN (-5425 1750) $PN BF13
J 2
(-5435 1760);
DISPLAY 0.489362 (-5435 1760);
PAINT MONO (-5435 1760);
FORCEPROP 0 LASTPIN (-5425 1700) $PN BG12
J 2
(-5435 1710);
DISPLAY 0.489362 (-5435 1710);
PAINT MONO (-5435 1710);
FORCEPROP 0 LASTPIN (-5425 2050) $PN AT14
J 2
(-5435 2060);
DISPLAY 0.489362 (-5435 2060);
PAINT MONO (-5435 2060);
FORCEPROP 0 LASTPIN (-5425 1950) $PN AU14
J 2
(-5435 1960);
DISPLAY 0.489362 (-5435 1960);
PAINT MONO (-5435 1960);
FORCEPROP 0 LASTPIN (-5425 2750) $PN AU12
J 2
(-5435 2760);
DISPLAY 0.489362 (-5435 2760);
PAINT MONO (-5435 2760);
FORCEPROP 0 LASTPIN (-5425 2700) $PN AV14
J 2
(-5435 2710);
DISPLAY 0.489362 (-5435 2710);
PAINT MONO (-5435 2710);
FORCEPROP 0 LASTPIN (-5425 2600) $PN BN14
J 2
(-5435 2610);
DISPLAY 0.489362 (-5435 2610);
PAINT MONO (-5435 2610);
FORCEPROP 0 LASTPIN (-5425 1600) $PN AV13
J 2
(-5435 1610);
DISPLAY 0.489362 (-5435 1610);
PAINT MONO (-5435 1610);
FORCEPROP 0 LASTPIN (-5425 1550) $PN AW14
J 2
(-5435 1560);
DISPLAY 0.489362 (-5435 1560);
PAINT MONO (-5435 1560);
FORCEPROP 0 LASTPIN (-5425 1450) $PN BP14
J 2
(-5435 1460);
DISPLAY 0.489362 (-5435 1460);
PAINT MONO (-5435 1460);
FORCEPROP 0 LASTPIN (-5425 3750) $PN AW12
J 2
(-5435 3760);
DISPLAY 0.489362 (-5435 3760);
PAINT MONO (-5435 3760);
FORCEPROP 0 LASTPIN (-5425 3700) $PN AY13
J 2
(-5435 3710);
DISPLAY 0.489362 (-5435 3710);
PAINT MONO (-5435 3710);
FORCEPROP 0 LASTPIN (-5425 3650) $PN AY14
J 2
(-5435 3660);
DISPLAY 0.489362 (-5435 3660);
PAINT MONO (-5435 3660);
FORCEPROP 0 LASTPIN (-5425 3600) $PN BA14
J 2
(-5435 3610);
DISPLAY 0.489362 (-5435 3610);
PAINT MONO (-5435 3610);
FORCEPROP 0 LASTPIN (-5425 3550) $PN BA12
J 2
(-5435 3560);
DISPLAY 0.489362 (-5435 3560);
PAINT MONO (-5435 3560);
FORCEPROP 0 LASTPIN (-5425 3500) $PN BB13
J 2
(-5435 3510);
DISPLAY 0.489362 (-5435 3510);
PAINT MONO (-5435 3510);
FORCEPROP 0 LASTPIN (-5425 3450) $PN BB14
J 2
(-5435 3460);
DISPLAY 0.489362 (-5435 3460);
PAINT MONO (-5435 3460);
FORCEPROP 0 LASTPIN (-3825 2300) $PN AJ12
J 0
(-3815 2310);
DISPLAY 0.489362 (-3815 2310);
PAINT MONO (-3815 2310);
FORCEPROP 0 LASTPIN (-3825 2250) $PN AK14
J 0
(-3815 2260);
DISPLAY 0.489362 (-3815 2260);
PAINT MONO (-3815 2260);
FORCEPROP 0 LASTPIN (-3825 2200) $PN AK13
J 0
(-3815 2210);
DISPLAY 0.489362 (-3815 2210);
PAINT MONO (-3815 2210);
FORCEPROP 0 LASTPIN (-3825 2150) $PN AL14
J 0
(-3815 2160);
DISPLAY 0.489362 (-3815 2160);
PAINT MONO (-3815 2160);
FORCEPROP 0 LASTPIN (-3825 2100) $PN AN12
J 0
(-3815 2110);
DISPLAY 0.489362 (-3815 2110);
PAINT MONO (-3815 2110);
FORCEPROP 0 LASTPIN (-3825 2050) $PN AP14
J 0
(-3815 2060);
DISPLAY 0.489362 (-3815 2060);
PAINT MONO (-3815 2060);
FORCEPROP 0 LASTPIN (-3825 2000) $PN AP13
J 0
(-3815 2010);
DISPLAY 0.489362 (-3815 2010);
PAINT MONO (-3815 2010);
FORCEPROP 0 LASTPIN (-3825 1950) $PN AR14
J 0
(-3815 1960);
DISPLAY 0.489362 (-3815 1960);
PAINT MONO (-3815 1960);
FORCEPROP 0 LASTPIN (-3825 5900) $PN E12
J 0
(-3815 5910);
DISPLAY 0.489362 (-3815 5910);
PAINT MONO (-3815 5910);
FORCEPROP 0 LASTPIN (-3825 5850) $PN F14
J 0
(-3815 5860);
DISPLAY 0.489362 (-3815 5860);
PAINT MONO (-3815 5860);
FORCEPROP 0 LASTPIN (-3825 5800) $PN F13
J 0
(-3815 5810);
DISPLAY 0.489362 (-3815 5810);
PAINT MONO (-3815 5810);
FORCEPROP 0 LASTPIN (-3825 5750) $PN G14
J 0
(-3815 5760);
DISPLAY 0.489362 (-3815 5760);
PAINT MONO (-3815 5760);
FORCEPROP 0 LASTPIN (-3825 5700) $PN J12
J 0
(-3815 5710);
DISPLAY 0.489362 (-3815 5710);
PAINT MONO (-3815 5710);
FORCEPROP 0 LASTPIN (-3825 5650) $PN K14
J 0
(-3815 5660);
DISPLAY 0.489362 (-3815 5660);
PAINT MONO (-3815 5660);
FORCEPROP 0 LASTPIN (-3825 5600) $PN K13
J 0
(-3815 5610);
DISPLAY 0.489362 (-3815 5610);
PAINT MONO (-3815 5610);
FORCEPROP 0 LASTPIN (-3825 5550) $PN L14
J 0
(-3815 5560);
DISPLAY 0.489362 (-3815 5560);
PAINT MONO (-3815 5560);
FORCEPROP 0 LASTPIN (-3825 5450) $PN L12
J 0
(-3815 5460);
DISPLAY 0.489362 (-3815 5460);
PAINT MONO (-3815 5460);
FORCEPROP 0 LASTPIN (-3825 5400) $PN M14
J 0
(-3815 5410);
DISPLAY 0.489362 (-3815 5410);
PAINT MONO (-3815 5410);
FORCEPROP 0 LASTPIN (-3825 5350) $PN M13
J 0
(-3815 5360);
DISPLAY 0.489362 (-3815 5360);
PAINT MONO (-3815 5360);
FORCEPROP 0 LASTPIN (-3825 5300) $PN N14
J 0
(-3815 5310);
DISPLAY 0.489362 (-3815 5310);
PAINT MONO (-3815 5310);
FORCEPROP 0 LASTPIN (-3825 5250) $PN R12
J 0
(-3815 5260);
DISPLAY 0.489362 (-3815 5260);
PAINT MONO (-3815 5260);
FORCEPROP 0 LASTPIN (-3825 5200) $PN T14
J 0
(-3815 5210);
DISPLAY 0.489362 (-3815 5210);
PAINT MONO (-3815 5210);
FORCEPROP 0 LASTPIN (-3825 5150) $PN T13
J 0
(-3815 5160);
DISPLAY 0.489362 (-3815 5160);
PAINT MONO (-3815 5160);
FORCEPROP 0 LASTPIN (-3825 5100) $PN U14
J 0
(-3815 5110);
DISPLAY 0.489362 (-3815 5110);
PAINT MONO (-3815 5110);
FORCEPROP 0 LASTPIN (-3825 5000) $PN U12
J 0
(-3815 5010);
DISPLAY 0.489362 (-3815 5010);
PAINT MONO (-3815 5010);
FORCEPROP 0 LASTPIN (-3825 4950) $PN V14
J 0
(-3815 4960);
DISPLAY 0.489362 (-3815 4960);
PAINT MONO (-3815 4960);
FORCEPROP 0 LASTPIN (-3825 4900) $PN V13
J 0
(-3815 4910);
DISPLAY 0.489362 (-3815 4910);
PAINT MONO (-3815 4910);
FORCEPROP 0 LASTPIN (-3825 4850) $PN W14
J 0
(-3815 4860);
DISPLAY 0.489362 (-3815 4860);
PAINT MONO (-3815 4860);
FORCEPROP 0 LASTPIN (-3825 4800) $PN AA12
J 0
(-3815 4810);
DISPLAY 0.489362 (-3815 4810);
PAINT MONO (-3815 4810);
FORCEPROP 0 LASTPIN (-3825 4750) $PN AB14
J 0
(-3815 4760);
DISPLAY 0.489362 (-3815 4760);
PAINT MONO (-3815 4760);
FORCEPROP 0 LASTPIN (-3825 4700) $PN AB13
J 0
(-3815 4710);
DISPLAY 0.489362 (-3815 4710);
PAINT MONO (-3815 4710);
FORCEPROP 0 LASTPIN (-3825 4650) $PN AC14
J 0
(-3815 4660);
DISPLAY 0.489362 (-3815 4660);
PAINT MONO (-3815 4660);
FORCEPROP 0 LASTPIN (-3825 4550) $PN AC12
J 0
(-3815 4560);
DISPLAY 0.489362 (-3815 4560);
PAINT MONO (-3815 4560);
FORCEPROP 0 LASTPIN (-3825 4500) $PN AD14
J 0
(-3815 4510);
DISPLAY 0.489362 (-3815 4510);
PAINT MONO (-3815 4510);
FORCEPROP 0 LASTPIN (-3825 4450) $PN AD13
J 0
(-3815 4460);
DISPLAY 0.489362 (-3815 4460);
PAINT MONO (-3815 4460);
FORCEPROP 0 LASTPIN (-3825 4400) $PN AE14
J 0
(-3815 4410);
DISPLAY 0.489362 (-3815 4410);
PAINT MONO (-3815 4410);
FORCEPROP 0 LASTPIN (-3825 4350) $PN AG12
J 0
(-3815 4360);
DISPLAY 0.489362 (-3815 4360);
PAINT MONO (-3815 4360);
FORCEPROP 0 LASTPIN (-3825 4300) $PN AH14
J 0
(-3815 4310);
DISPLAY 0.489362 (-3815 4310);
PAINT MONO (-3815 4310);
FORCEPROP 0 LASTPIN (-3825 4250) $PN AH13
J 0
(-3815 4260);
DISPLAY 0.489362 (-3815 4260);
PAINT MONO (-3815 4260);
FORCEPROP 0 LASTPIN (-3825 4200) $PN AJ14
J 0
(-3815 4210);
DISPLAY 0.489362 (-3815 4210);
PAINT MONO (-3815 4210);
FORCEPROP 0 LASTPIN (-5425 5900) $PN G12
J 2
(-5435 5910);
DISPLAY 0.489362 (-5435 5910);
PAINT MONO (-5435 5910);
FORCEPROP 0 LASTPIN (-5425 5800) $PN N12
J 2
(-5435 5810);
DISPLAY 0.489362 (-5435 5810);
PAINT MONO (-5435 5810);
FORCEPROP 0 LASTPIN (-5425 5700) $PN W12
J 2
(-5435 5710);
DISPLAY 0.489362 (-5435 5710);
PAINT MONO (-5435 5710);
FORCEPROP 0 LASTPIN (-5425 5600) $PN AE12
J 2
(-5435 5610);
DISPLAY 0.489362 (-5435 5610);
PAINT MONO (-5435 5610);
FORCEPROP 0 LASTPIN (-5425 5500) $PN AL12
J 2
(-5435 5510);
DISPLAY 0.489362 (-5435 5510);
PAINT MONO (-5435 5510);
FORCEPROP 0 LASTPIN (-5425 5400) $PN J14
J 2
(-5435 5410);
DISPLAY 0.489362 (-5435 5410);
PAINT MONO (-5435 5410);
FORCEPROP 0 LASTPIN (-5425 5300) $PN R14
J 2
(-5435 5310);
DISPLAY 0.489362 (-5435 5310);
PAINT MONO (-5435 5310);
FORCEPROP 0 LASTPIN (-5425 5200) $PN AA14
J 2
(-5435 5210);
DISPLAY 0.489362 (-5435 5210);
PAINT MONO (-5435 5210);
FORCEPROP 0 LASTPIN (-5425 5100) $PN AG14
J 2
(-5435 5110);
DISPLAY 0.489362 (-5435 5110);
PAINT MONO (-5435 5110);
FORCEPROP 0 LASTPIN (-5425 5000) $PN AN14
J 2
(-5435 5010);
DISPLAY 0.489362 (-5435 5010);
PAINT MONO (-5435 5010);
FORCEPROP 0 LASTPIN (-5425 5850) $PN H13
J 2
(-5435 5860);
DISPLAY 0.489362 (-5435 5860);
PAINT MONO (-5435 5860);
FORCEPROP 0 LASTPIN (-5425 5750) $PN P13
J 2
(-5435 5760);
DISPLAY 0.489362 (-5435 5760);
PAINT MONO (-5435 5760);
FORCEPROP 0 LASTPIN (-5425 5650) $PN Y13
J 2
(-5435 5660);
DISPLAY 0.489362 (-5435 5660);
PAINT MONO (-5435 5660);
FORCEPROP 0 LASTPIN (-5425 5550) $PN AF13
J 2
(-5435 5560);
DISPLAY 0.489362 (-5435 5560);
PAINT MONO (-5435 5560);
FORCEPROP 0 LASTPIN (-5425 5450) $PN AM13
J 2
(-5435 5460);
DISPLAY 0.489362 (-5435 5460);
PAINT MONO (-5435 5460);
FORCEPROP 0 LASTPIN (-5425 5350) $PN H14
J 2
(-5435 5360);
DISPLAY 0.489362 (-5435 5360);
PAINT MONO (-5435 5360);
FORCEPROP 0 LASTPIN (-5425 5250) $PN P14
J 2
(-5435 5260);
DISPLAY 0.489362 (-5435 5260);
PAINT MONO (-5435 5260);
FORCEPROP 0 LASTPIN (-5425 5150) $PN Y14
J 2
(-5435 5160);
DISPLAY 0.489362 (-5435 5160);
PAINT MONO (-5435 5160);
FORCEPROP 0 LASTPIN (-5425 5050) $PN AF14
J 2
(-5435 5060);
DISPLAY 0.489362 (-5435 5060);
PAINT MONO (-5435 5060);
FORCEPROP 0 LASTPIN (-5425 4950) $PN AM14
J 2
(-5435 4960);
DISPLAY 0.489362 (-5435 4960);
PAINT MONO (-5435 4960);
FORCEPROP 0 LASTPIN (-5425 2500) $PN BC14
J 2
(-5435 2510);
DISPLAY 0.489362 (-5435 2510);
PAINT MONO (-5435 2510);
FORCEPROP 0 LASTPIN (-5425 2400) $PN BM14
J 2
(-5435 2410);
DISPLAY 0.489362 (-5435 2410);
PAINT MONO (-5435 2410);
FORCEPROP 0 LASTPIN (-5425 2350) $PN BN12
J 2
(-5435 2360);
DISPLAY 0.489362 (-5435 2360);
PAINT MONO (-5435 2360);
FORCEPROP 0 LASTPIN (-5425 2250) $PN BP13
J 2
(-5435 2260);
DISPLAY 0.489362 (-5435 2260);
PAINT MONO (-5435 2260);
FORCEPROP 0 LASTPIN (-5425 1350) $PN BL12
J 2
(-5435 1360);
DISPLAY 0.489362 (-5435 1360);
PAINT MONO (-5435 1360);
FORCEPROP 0 LASTPIN (-5425 1300) $PN BM13
J 2
(-5435 1310);
DISPLAY 0.489362 (-5435 1310);
PAINT MONO (-5435 1310);
FORCEPROP 0 LASTPIN (-5425 1200) $PN BR12
J 2
(-5435 1210);
DISPLAY 0.489362 (-5435 1210);
PAINT MONO (-5435 1210);
FORCEPROP 0 LASTPIN (-5425 3350) $PN BG14
J 2
(-5435 3360);
DISPLAY 0.489362 (-5435 3360);
PAINT MONO (-5435 3360);
FORCEPROP 0 LASTPIN (-5425 3300) $PN BH14
J 2
(-5435 3310);
DISPLAY 0.489362 (-5435 3310);
PAINT MONO (-5435 3310);
FORCEPROP 0 LASTPIN (-5425 3250) $PN BH13
J 2
(-5435 3260);
DISPLAY 0.489362 (-5435 3260);
PAINT MONO (-5435 3260);
FORCEPROP 0 LASTPIN (-5425 3200) $PN BJ12
J 2
(-5435 3210);
DISPLAY 0.489362 (-5435 3210);
PAINT MONO (-5435 3210);
FORCEPROP 0 LASTPIN (-5425 3150) $PN BJ14
J 2
(-5435 3160);
DISPLAY 0.489362 (-5435 3160);
PAINT MONO (-5435 3160);
FORCEPROP 0 LASTPIN (-5425 3100) $PN BK14
J 2
(-5435 3110);
DISPLAY 0.489362 (-5435 3110);
PAINT MONO (-5435 3110);
FORCEPROP 0 LASTPIN (-5425 3050) $PN BK13
J 2
(-5435 3060);
DISPLAY 0.489362 (-5435 3060);
PAINT MONO (-5435 3060);
FORCEPROP 0 LASTPIN (-3825 1850) $PN BY13
J 0
(-3815 1860);
DISPLAY 0.489362 (-3815 1860);
PAINT MONO (-3815 1860);
FORCEPROP 0 LASTPIN (-3825 1800) $PN CA14
J 0
(-3815 1810);
DISPLAY 0.489362 (-3815 1810);
PAINT MONO (-3815 1810);
FORCEPROP 0 LASTPIN (-3825 1750) $PN CA12
J 0
(-3815 1760);
DISPLAY 0.489362 (-3815 1760);
PAINT MONO (-3815 1760);
FORCEPROP 0 LASTPIN (-3825 1700) $PN CB14
J 0
(-3815 1710);
DISPLAY 0.489362 (-3815 1710);
PAINT MONO (-3815 1710);
FORCEPROP 0 LASTPIN (-3825 1650) $PN BT13
J 0
(-3815 1660);
DISPLAY 0.489362 (-3815 1660);
PAINT MONO (-3815 1660);
FORCEPROP 0 LASTPIN (-3825 1600) $PN BU14
J 0
(-3815 1610);
DISPLAY 0.489362 (-3815 1610);
PAINT MONO (-3815 1610);
FORCEPROP 0 LASTPIN (-3825 1550) $PN BU12
J 0
(-3815 1560);
DISPLAY 0.489362 (-3815 1560);
PAINT MONO (-3815 1560);
FORCEPROP 0 LASTPIN (-3825 1500) $PN BV14
J 0
(-3815 1510);
DISPLAY 0.489362 (-3815 1510);
PAINT MONO (-3815 1510);
FORCEPROP 0 LASTPIN (-3825 4100) $PN CB13
J 0
(-3815 4110);
DISPLAY 0.489362 (-3815 4110);
PAINT MONO (-3815 4110);
FORCEPROP 0 LASTPIN (-3825 4050) $PN CC14
J 0
(-3815 4060);
DISPLAY 0.489362 (-3815 4060);
PAINT MONO (-3815 4060);
FORCEPROP 0 LASTPIN (-3825 4000) $PN CC12
J 0
(-3815 4010);
DISPLAY 0.489362 (-3815 4010);
PAINT MONO (-3815 4010);
FORCEPROP 0 LASTPIN (-3825 3950) $PN CD14
J 0
(-3815 3960);
DISPLAY 0.489362 (-3815 3960);
PAINT MONO (-3815 3960);
FORCEPROP 0 LASTPIN (-3825 3900) $PN CF13
J 0
(-3815 3910);
DISPLAY 0.489362 (-3815 3910);
PAINT MONO (-3815 3910);
FORCEPROP 0 LASTPIN (-3825 3850) $PN CG14
J 0
(-3815 3860);
DISPLAY 0.489362 (-3815 3860);
PAINT MONO (-3815 3860);
FORCEPROP 0 LASTPIN (-3825 3800) $PN CG12
J 0
(-3815 3810);
DISPLAY 0.489362 (-3815 3810);
PAINT MONO (-3815 3810);
FORCEPROP 0 LASTPIN (-3825 3750) $PN CH14
J 0
(-3815 3760);
DISPLAY 0.489362 (-3815 3760);
PAINT MONO (-3815 3760);
FORCEPROP 0 LASTPIN (-3825 3650) $PN CH13
J 0
(-3815 3660);
DISPLAY 0.489362 (-3815 3660);
PAINT MONO (-3815 3660);
FORCEPROP 0 LASTPIN (-3825 3600) $PN CJ14
J 0
(-3815 3610);
DISPLAY 0.489362 (-3815 3610);
PAINT MONO (-3815 3610);
FORCEPROP 0 LASTPIN (-3825 3550) $PN CJ12
J 0
(-3815 3560);
DISPLAY 0.489362 (-3815 3560);
PAINT MONO (-3815 3560);
FORCEPROP 0 LASTPIN (-3825 3500) $PN CK14
J 0
(-3815 3510);
DISPLAY 0.489362 (-3815 3510);
PAINT MONO (-3815 3510);
FORCEPROP 0 LASTPIN (-3825 3450) $PN CM13
J 0
(-3815 3460);
DISPLAY 0.489362 (-3815 3460);
PAINT MONO (-3815 3460);
FORCEPROP 0 LASTPIN (-3825 3400) $PN CN14
J 0
(-3815 3410);
DISPLAY 0.489362 (-3815 3410);
PAINT MONO (-3815 3410);
FORCEPROP 0 LASTPIN (-3825 3350) $PN CN12
J 0
(-3815 3360);
DISPLAY 0.489362 (-3815 3360);
PAINT MONO (-3815 3360);
FORCEPROP 0 LASTPIN (-3825 3300) $PN CP14
J 0
(-3815 3310);
DISPLAY 0.489362 (-3815 3310);
PAINT MONO (-3815 3310);
FORCEPROP 0 LASTPIN (-3825 3200) $PN CP13
J 0
(-3815 3210);
DISPLAY 0.489362 (-3815 3210);
PAINT MONO (-3815 3210);
FORCEPROP 0 LASTPIN (-3825 3150) $PN CR14
J 0
(-3815 3160);
DISPLAY 0.489362 (-3815 3160);
PAINT MONO (-3815 3160);
FORCEPROP 0 LASTPIN (-3825 3100) $PN CR12
J 0
(-3815 3110);
DISPLAY 0.489362 (-3815 3110);
PAINT MONO (-3815 3110);
FORCEPROP 0 LASTPIN (-3825 3050) $PN CT14
J 0
(-3815 3060);
DISPLAY 0.489362 (-3815 3060);
PAINT MONO (-3815 3060);
FORCEPROP 0 LASTPIN (-3825 3000) $PN CV13
J 0
(-3815 3010);
DISPLAY 0.489362 (-3815 3010);
PAINT MONO (-3815 3010);
FORCEPROP 0 LASTPIN (-3825 2950) $PN CW14
J 0
(-3815 2960);
DISPLAY 0.489362 (-3815 2960);
PAINT MONO (-3815 2960);
FORCEPROP 0 LASTPIN (-3825 2900) $PN CW12
J 0
(-3815 2910);
DISPLAY 0.489362 (-3815 2910);
PAINT MONO (-3815 2910);
FORCEPROP 0 LASTPIN (-3825 2850) $PN CY14
J 0
(-3815 2860);
DISPLAY 0.489362 (-3815 2860);
PAINT MONO (-3815 2860);
FORCEPROP 0 LASTPIN (-3825 2750) $PN CY13
J 0
(-3815 2760);
DISPLAY 0.489362 (-3815 2760);
PAINT MONO (-3815 2760);
FORCEPROP 0 LASTPIN (-3825 2700) $PN DA14
J 0
(-3815 2710);
DISPLAY 0.489362 (-3815 2710);
PAINT MONO (-3815 2710);
FORCEPROP 0 LASTPIN (-3825 2650) $PN DA12
J 0
(-3815 2660);
DISPLAY 0.489362 (-3815 2660);
PAINT MONO (-3815 2660);
FORCEPROP 0 LASTPIN (-3825 2600) $PN DB14
J 0
(-3815 2610);
DISPLAY 0.489362 (-3815 2610);
PAINT MONO (-3815 2610);
FORCEPROP 0 LASTPIN (-3825 2550) $PN DD13
J 0
(-3815 2560);
DISPLAY 0.489362 (-3815 2560);
PAINT MONO (-3815 2560);
FORCEPROP 0 LASTPIN (-3825 2500) $PN DE14
J 0
(-3815 2510);
DISPLAY 0.489362 (-3815 2510);
PAINT MONO (-3815 2510);
FORCEPROP 0 LASTPIN (-3825 2450) $PN DE12
J 0
(-3815 2460);
DISPLAY 0.489362 (-3815 2460);
PAINT MONO (-3815 2460);
FORCEPROP 0 LASTPIN (-3825 2400) $PN DF14
J 0
(-3815 2410);
DISPLAY 0.489362 (-3815 2410);
PAINT MONO (-3815 2410);
FORCEPROP 0 LASTPIN (-5425 4850) $PN CD13
J 2
(-5435 4860);
DISPLAY 0.489362 (-5435 4860);
PAINT MONO (-5435 4860);
FORCEPROP 0 LASTPIN (-5425 4750) $PN CK13
J 2
(-5435 4760);
DISPLAY 0.489362 (-5435 4760);
PAINT MONO (-5435 4760);
FORCEPROP 0 LASTPIN (-5425 4650) $PN CT13
J 2
(-5435 4660);
DISPLAY 0.489362 (-5435 4660);
PAINT MONO (-5435 4660);
FORCEPROP 0 LASTPIN (-5425 4550) $PN DB13
J 2
(-5435 4560);
DISPLAY 0.489362 (-5435 4560);
PAINT MONO (-5435 4560);
FORCEPROP 0 LASTPIN (-5425 4450) $PN BY14
J 2
(-5435 4460);
DISPLAY 0.489362 (-5435 4460);
PAINT MONO (-5435 4460);
FORCEPROP 0 LASTPIN (-5425 4350) $PN CF14
J 2
(-5435 4360);
DISPLAY 0.489362 (-5435 4360);
PAINT MONO (-5435 4360);
FORCEPROP 0 LASTPIN (-5425 4250) $PN CM14
J 2
(-5435 4260);
DISPLAY 0.489362 (-5435 4260);
PAINT MONO (-5435 4260);
FORCEPROP 0 LASTPIN (-5425 4150) $PN CV14
J 2
(-5435 4160);
DISPLAY 0.489362 (-5435 4160);
PAINT MONO (-5435 4160);
FORCEPROP 0 LASTPIN (-5425 4050) $PN DD14
J 2
(-5435 4060);
DISPLAY 0.489362 (-5435 4060);
PAINT MONO (-5435 4060);
FORCEPROP 0 LASTPIN (-5425 3950) $PN BV13
J 2
(-5435 3960);
DISPLAY 0.489362 (-5435 3960);
PAINT MONO (-5435 3960);
FORCEPROP 0 LASTPIN (-5425 4800) $PN CE12
J 2
(-5435 4810);
DISPLAY 0.489362 (-5435 4810);
PAINT MONO (-5435 4810);
FORCEPROP 0 LASTPIN (-5425 4700) $PN CL12
J 2
(-5435 4710);
DISPLAY 0.489362 (-5435 4710);
PAINT MONO (-5435 4710);
FORCEPROP 0 LASTPIN (-5425 4600) $PN CU12
J 2
(-5435 4610);
DISPLAY 0.489362 (-5435 4610);
PAINT MONO (-5435 4610);
FORCEPROP 0 LASTPIN (-5425 4500) $PN DC12
J 2
(-5435 4510);
DISPLAY 0.489362 (-5435 4510);
PAINT MONO (-5435 4510);
FORCEPROP 0 LASTPIN (-5425 4400) $PN BW14
J 2
(-5435 4410);
DISPLAY 0.489362 (-5435 4410);
PAINT MONO (-5435 4410);
FORCEPROP 0 LASTPIN (-5425 4300) $PN CE14
J 2
(-5435 4310);
DISPLAY 0.489362 (-5435 4310);
PAINT MONO (-5435 4310);
FORCEPROP 0 LASTPIN (-5425 4200) $PN CL14
J 2
(-5435 4210);
DISPLAY 0.489362 (-5435 4210);
PAINT MONO (-5435 4210);
FORCEPROP 0 LASTPIN (-5425 4100) $PN CU14
J 2
(-5435 4110);
DISPLAY 0.489362 (-5435 4110);
PAINT MONO (-5435 4110);
FORCEPROP 0 LASTPIN (-5425 4000) $PN DC14
J 2
(-5435 4010);
DISPLAY 0.489362 (-5435 4010);
PAINT MONO (-5435 4010);
FORCEPROP 0 LASTPIN (-5425 3900) $PN BW12
J 2
(-5435 3910);
DISPLAY 0.489362 (-5435 3910);
PAINT MONO (-5435 3910);
FORCEPROP 0 LASTPIN (-5425 2150) $PN BL14
J 2
(-5435 2160);
DISPLAY 0.489362 (-5435 2160);
PAINT MONO (-5435 2160);
FORCEPROP 0 LASTPIN (-5425 1100) $PN BF14
J 2
(-5435 1110);
DISPLAY 0.489362 (-5435 1110);
PAINT MONO (-5435 1110);
FORCEPROP 2 LAST PART_TYPE SMLF
J 0
(-5275 6300);
DISPLAY 1.021277 (-5275 6300);
FORCEPROP 1 LAST MATERIAL IO
J 0
(-5270 6082);
DISPLAY 0.489362 (-5270 6082);
PAINT SKYBLUE (-5270 6082);
FORCEPROP 2 LAST VALUE SOCKET6096_13568-001
J 0
(-5275 6200);
DISPLAY 0.489362 (-5275 6200);
PAINT SKYBLUE (-5275 6200);
FORCEPROP 2 LAST CDS_LIB pure_quanta
J 0
(-4625 3525);
DISPLAY INVISIBLE (-4625 3525);
FORCEPROP 1 LAST CDS_LMAN_SYM_OUTLINE -650,2525,650,-2525
J 0
(-4625 3525);
DISPLAY 0.468085 (-4625 3525);
PAINT GREEN (-4625 3525);
DISPLAY INVISIBLE (-4625 3525);
FORCEPROP 1 LAST NEEDS_NO_SIZE TRUE
J 0
(-4625 3525);
DISPLAY 0.723404 (-4625 3525);
PAINT GREEN (-4625 3525);
DISPLAY INVISIBLE (-4625 3525);
FORCEPROP 1 LAST PATH I159
J 0
(-4625 3525);
DISPLAY 0.723404 (-4625 3525);
PAINT GREEN (-4625 3525);
DISPLAY INVISIBLE (-4625 3525);
FORCEPROP 1 LAST PART_NUMBER DGA^6000030
J 0
(-5270 6209);
DISPLAY 0.489362 (-5270 6209);
PAINT SKYBLUE (-5270 6209);
DISPLAY INVISIBLE (-5270 6209);
FORCEADD OFFPAGE..3
(-2625 5925);
FORCEPROP 2 LAST $XR0 105 
J 0
(-2411 5925);
DISPLAY 0.638298 (-2411 5925);
PAINT MONO (-2411 5925);
FORCEPROP 2 LAST CDS_LIB mstr_standard
J 0
(-2625 5925);
DISPLAY 0.723404 (-2625 5925);
PAINT MONO (-2625 5925);
DISPLAY INVISIBLE (-2625 5925);
FORCEPROP 1 LAST OFFPAGE TRUE
J 0
(-2300 5800);
DISPLAY 0.872340 (-2300 5800);
PAINT GREEN (-2300 5800);
DISPLAY INVISIBLE (-2300 5800);
FORCEPROP 1 LAST COMMENT_BODY TRUE
J 0
(-2675 5825);
DISPLAY 0.872340 (-2675 5825);
PAINT GREEN (-2675 5825);
DISPLAY INVISIBLE (-2675 5825);
FORCEPROP 2 LAST PATH I160
J 0
(-2400 5975);
DISPLAY 1.021277 (-2400 5975);
DISPLAY INVISIBLE (-2400 5975);
FORCEADD TAP..1
(-3350 5900);
FORCEPROP 3 LASTPIN (-3400 5900) SIG_NAME M_H_CPU1_SA_DQ<0>
J 0
(-3390 5910);
DISPLAY 0.659574 (-3390 5910);
PAINT MONO (-3390 5910);
DISPLAY INVISIBLE (-3390 5910);
FORCEPROP 1 LASTPIN (-3400 5900) BN 0
J 0
(-3412 5908);
DISPLAY 0.489362 (-3412 5908);
PAINT GREEN (-3412 5908);
FORCEPROP 2 LAST CDS_LIB mstr_standard
J 0
(-3350 5900);
DISPLAY 0.723404 (-3350 5900);
PAINT MONO (-3350 5900);
DISPLAY INVISIBLE (-3350 5900);
FORCEPROP 1 LAST BODY_TYPE PLUMBING
J 0
(-3350 5950);
DISPLAY 0.872340 (-3350 5950);
PAINT GREEN (-3350 5950);
DISPLAY INVISIBLE (-3350 5950);
FORCEPROP 1 LAST HDL_TAP TRUE
J 0
(-3025 5775);
DISPLAY 0.872340 (-3025 5775);
DISPLAY INVISIBLE (-3025 5775);
FORCEPROP 1 LAST PATH I161
J 0
(-3352 5900);
DISPLAY 0.872340 (-3352 5900);
PAINT GREEN (-3352 5900);
DISPLAY INVISIBLE (-3352 5900);
FORCEADD TAP..1
(-3350 5800);
FORCEPROP 3 LASTPIN (-3400 5800) SIG_NAME M_H_CPU1_SA_DQ<2>
J 0
(-3390 5810);
DISPLAY 0.659574 (-3390 5810);
PAINT MONO (-3390 5810);
DISPLAY INVISIBLE (-3390 5810);
FORCEPROP 1 LASTPIN (-3400 5800) BN 2
J 0
(-3412 5808);
DISPLAY 0.489362 (-3412 5808);
PAINT GREEN (-3412 5808);
FORCEPROP 2 LAST CDS_LIB mstr_standard
J 0
(-3350 5800);
DISPLAY 0.723404 (-3350 5800);
PAINT MONO (-3350 5800);
DISPLAY INVISIBLE (-3350 5800);
FORCEPROP 1 LAST BODY_TYPE PLUMBING
J 0
(-3350 5850);
DISPLAY 0.872340 (-3350 5850);
PAINT GREEN (-3350 5850);
DISPLAY INVISIBLE (-3350 5850);
FORCEPROP 1 LAST HDL_TAP TRUE
J 0
(-3025 5675);
DISPLAY 0.872340 (-3025 5675);
DISPLAY INVISIBLE (-3025 5675);
FORCEPROP 1 LAST PATH I162
J 0
(-3352 5800);
DISPLAY 0.872340 (-3352 5800);
PAINT GREEN (-3352 5800);
DISPLAY INVISIBLE (-3352 5800);
FORCEADD TAP..1
(-3350 5850);
FORCEPROP 3 LASTPIN (-3400 5850) SIG_NAME M_H_CPU1_SA_DQ<1>
J 0
(-3390 5860);
DISPLAY 0.659574 (-3390 5860);
PAINT MONO (-3390 5860);
DISPLAY INVISIBLE (-3390 5860);
FORCEPROP 1 LASTPIN (-3400 5850) BN 1
J 0
(-3412 5858);
DISPLAY 0.489362 (-3412 5858);
PAINT GREEN (-3412 5858);
FORCEPROP 2 LAST CDS_LIB mstr_standard
J 0
(-3350 5850);
DISPLAY 0.723404 (-3350 5850);
PAINT MONO (-3350 5850);
DISPLAY INVISIBLE (-3350 5850);
FORCEPROP 1 LAST BODY_TYPE PLUMBING
J 0
(-3350 5900);
DISPLAY 0.872340 (-3350 5900);
PAINT GREEN (-3350 5900);
DISPLAY INVISIBLE (-3350 5900);
FORCEPROP 1 LAST HDL_TAP TRUE
J 0
(-3025 5725);
DISPLAY 0.872340 (-3025 5725);
DISPLAY INVISIBLE (-3025 5725);
FORCEPROP 1 LAST PATH I163
J 0
(-3352 5850);
DISPLAY 0.872340 (-3352 5850);
PAINT GREEN (-3352 5850);
DISPLAY INVISIBLE (-3352 5850);
FORCEADD TAP..1
(-3350 5750);
FORCEPROP 3 LASTPIN (-3400 5750) SIG_NAME M_H_CPU1_SA_DQ<3>
J 0
(-3390 5760);
DISPLAY 0.659574 (-3390 5760);
PAINT MONO (-3390 5760);
DISPLAY INVISIBLE (-3390 5760);
FORCEPROP 1 LASTPIN (-3400 5750) BN 3
J 0
(-3412 5758);
DISPLAY 0.489362 (-3412 5758);
PAINT GREEN (-3412 5758);
FORCEPROP 2 LAST CDS_LIB mstr_standard
J 0
(-3350 5750);
DISPLAY 0.723404 (-3350 5750);
PAINT MONO (-3350 5750);
DISPLAY INVISIBLE (-3350 5750);
FORCEPROP 1 LAST BODY_TYPE PLUMBING
J 0
(-3350 5800);
DISPLAY 0.872340 (-3350 5800);
PAINT GREEN (-3350 5800);
DISPLAY INVISIBLE (-3350 5800);
FORCEPROP 1 LAST HDL_TAP TRUE
J 0
(-3025 5625);
DISPLAY 0.872340 (-3025 5625);
DISPLAY INVISIBLE (-3025 5625);
FORCEPROP 1 LAST PATH I164
J 0
(-3352 5750);
DISPLAY 0.872340 (-3352 5750);
PAINT GREEN (-3352 5750);
DISPLAY INVISIBLE (-3352 5750);
FORCEADD TAP..1
(-3350 5700);
FORCEPROP 3 LASTPIN (-3400 5700) SIG_NAME M_H_CPU1_SA_DQ<4>
J 0
(-3390 5710);
DISPLAY 0.659574 (-3390 5710);
PAINT MONO (-3390 5710);
DISPLAY INVISIBLE (-3390 5710);
FORCEPROP 1 LASTPIN (-3400 5700) BN 4
J 0
(-3412 5708);
DISPLAY 0.489362 (-3412 5708);
PAINT GREEN (-3412 5708);
FORCEPROP 2 LAST CDS_LIB mstr_standard
J 0
(-3350 5700);
DISPLAY 0.723404 (-3350 5700);
PAINT MONO (-3350 5700);
DISPLAY INVISIBLE (-3350 5700);
FORCEPROP 1 LAST BODY_TYPE PLUMBING
J 0
(-3350 5750);
DISPLAY 0.872340 (-3350 5750);
PAINT GREEN (-3350 5750);
DISPLAY INVISIBLE (-3350 5750);
FORCEPROP 1 LAST HDL_TAP TRUE
J 0
(-3025 5575);
DISPLAY 0.872340 (-3025 5575);
DISPLAY INVISIBLE (-3025 5575);
FORCEPROP 1 LAST PATH I165
J 0
(-3352 5700);
DISPLAY 0.872340 (-3352 5700);
PAINT GREEN (-3352 5700);
DISPLAY INVISIBLE (-3352 5700);
FORCEADD TAP..1
(-3350 5650);
FORCEPROP 3 LASTPIN (-3400 5650) SIG_NAME M_H_CPU1_SA_DQ<5>
J 0
(-3390 5660);
DISPLAY 0.659574 (-3390 5660);
PAINT MONO (-3390 5660);
DISPLAY INVISIBLE (-3390 5660);
FORCEPROP 1 LASTPIN (-3400 5650) BN 5
J 0
(-3412 5658);
DISPLAY 0.489362 (-3412 5658);
PAINT GREEN (-3412 5658);
FORCEPROP 2 LAST CDS_LIB mstr_standard
J 0
(-3350 5650);
DISPLAY 0.723404 (-3350 5650);
PAINT MONO (-3350 5650);
DISPLAY INVISIBLE (-3350 5650);
FORCEPROP 1 LAST BODY_TYPE PLUMBING
J 0
(-3350 5700);
DISPLAY 0.872340 (-3350 5700);
PAINT GREEN (-3350 5700);
DISPLAY INVISIBLE (-3350 5700);
FORCEPROP 1 LAST HDL_TAP TRUE
J 0
(-3025 5525);
DISPLAY 0.872340 (-3025 5525);
DISPLAY INVISIBLE (-3025 5525);
FORCEPROP 1 LAST PATH I166
J 0
(-3352 5650);
DISPLAY 0.872340 (-3352 5650);
PAINT GREEN (-3352 5650);
DISPLAY INVISIBLE (-3352 5650);
FORCEADD TAP..1
(-3350 5400);
FORCEPROP 3 LASTPIN (-3400 5400) SIG_NAME M_H_CPU1_SA_DQ<9>
J 0
(-3390 5410);
DISPLAY 0.659574 (-3390 5410);
PAINT MONO (-3390 5410);
DISPLAY INVISIBLE (-3390 5410);
FORCEPROP 1 LASTPIN (-3400 5400) BN 9
J 0
(-3412 5408);
DISPLAY 0.489362 (-3412 5408);
PAINT GREEN (-3412 5408);
FORCEPROP 2 LAST CDS_LIB mstr_standard
J 0
(-3350 5400);
DISPLAY 0.723404 (-3350 5400);
PAINT MONO (-3350 5400);
DISPLAY INVISIBLE (-3350 5400);
FORCEPROP 1 LAST BODY_TYPE PLUMBING
J 0
(-3350 5450);
DISPLAY 0.872340 (-3350 5450);
PAINT GREEN (-3350 5450);
DISPLAY INVISIBLE (-3350 5450);
FORCEPROP 1 LAST HDL_TAP TRUE
J 0
(-3025 5275);
DISPLAY 0.872340 (-3025 5275);
DISPLAY INVISIBLE (-3025 5275);
FORCEPROP 1 LAST PATH I167
J 0
(-3352 5400);
DISPLAY 0.872340 (-3352 5400);
PAINT GREEN (-3352 5400);
DISPLAY INVISIBLE (-3352 5400);
FORCEADD TAP..1
(-3350 5550);
FORCEPROP 3 LASTPIN (-3400 5550) SIG_NAME M_H_CPU1_SA_DQ<7>
J 0
(-3390 5560);
DISPLAY 0.659574 (-3390 5560);
PAINT MONO (-3390 5560);
DISPLAY INVISIBLE (-3390 5560);
FORCEPROP 1 LASTPIN (-3400 5550) BN 7
J 0
(-3412 5558);
DISPLAY 0.489362 (-3412 5558);
PAINT GREEN (-3412 5558);
FORCEPROP 2 LAST CDS_LIB mstr_standard
J 0
(-3350 5550);
DISPLAY 0.723404 (-3350 5550);
PAINT MONO (-3350 5550);
DISPLAY INVISIBLE (-3350 5550);
FORCEPROP 1 LAST BODY_TYPE PLUMBING
J 0
(-3350 5600);
DISPLAY 0.872340 (-3350 5600);
PAINT GREEN (-3350 5600);
DISPLAY INVISIBLE (-3350 5600);
FORCEPROP 1 LAST HDL_TAP TRUE
J 0
(-3025 5425);
DISPLAY 0.872340 (-3025 5425);
DISPLAY INVISIBLE (-3025 5425);
FORCEPROP 1 LAST PATH I168
J 0
(-3352 5550);
DISPLAY 0.872340 (-3352 5550);
PAINT GREEN (-3352 5550);
DISPLAY INVISIBLE (-3352 5550);
FORCEADD TAP..1
(-3350 5600);
FORCEPROP 3 LASTPIN (-3400 5600) SIG_NAME M_H_CPU1_SA_DQ<6>
J 0
(-3390 5610);
DISPLAY 0.659574 (-3390 5610);
PAINT MONO (-3390 5610);
DISPLAY INVISIBLE (-3390 5610);
FORCEPROP 1 LASTPIN (-3400 5600) BN 6
J 0
(-3412 5608);
DISPLAY 0.489362 (-3412 5608);
PAINT GREEN (-3412 5608);
FORCEPROP 2 LAST CDS_LIB mstr_standard
J 0
(-3350 5600);
DISPLAY 0.723404 (-3350 5600);
PAINT MONO (-3350 5600);
DISPLAY INVISIBLE (-3350 5600);
FORCEPROP 1 LAST BODY_TYPE PLUMBING
J 0
(-3350 5650);
DISPLAY 0.872340 (-3350 5650);
PAINT GREEN (-3350 5650);
DISPLAY INVISIBLE (-3350 5650);
FORCEPROP 1 LAST HDL_TAP TRUE
J 0
(-3025 5475);
DISPLAY 0.872340 (-3025 5475);
DISPLAY INVISIBLE (-3025 5475);
FORCEPROP 1 LAST PATH I169
J 0
(-3352 5600);
DISPLAY 0.872340 (-3352 5600);
PAINT GREEN (-3352 5600);
DISPLAY INVISIBLE (-3352 5600);
FORCEADD TAP..1
(-3350 5450);
FORCEPROP 3 LASTPIN (-3400 5450) SIG_NAME M_H_CPU1_SA_DQ<8>
J 0
(-3390 5460);
DISPLAY 0.659574 (-3390 5460);
PAINT MONO (-3390 5460);
DISPLAY INVISIBLE (-3390 5460);
FORCEPROP 1 LASTPIN (-3400 5450) BN 8
J 0
(-3412 5458);
DISPLAY 0.489362 (-3412 5458);
PAINT GREEN (-3412 5458);
FORCEPROP 2 LAST CDS_LIB mstr_standard
J 0
(-3350 5450);
DISPLAY 0.723404 (-3350 5450);
PAINT MONO (-3350 5450);
DISPLAY INVISIBLE (-3350 5450);
FORCEPROP 1 LAST BODY_TYPE PLUMBING
J 0
(-3350 5500);
DISPLAY 0.872340 (-3350 5500);
PAINT GREEN (-3350 5500);
DISPLAY INVISIBLE (-3350 5500);
FORCEPROP 1 LAST HDL_TAP TRUE
J 0
(-3025 5325);
DISPLAY 0.872340 (-3025 5325);
DISPLAY INVISIBLE (-3025 5325);
FORCEPROP 1 LAST PATH I170
J 0
(-3352 5450);
DISPLAY 0.872340 (-3352 5450);
PAINT GREEN (-3352 5450);
DISPLAY INVISIBLE (-3352 5450);
FORCEADD TAP..1
(-3350 5350);
FORCEPROP 3 LASTPIN (-3400 5350) SIG_NAME M_H_CPU1_SA_DQ<10>
J 0
(-3390 5360);
DISPLAY 0.659574 (-3390 5360);
PAINT MONO (-3390 5360);
DISPLAY INVISIBLE (-3390 5360);
FORCEPROP 1 LASTPIN (-3400 5350) BN 10
J 0
(-3412 5358);
DISPLAY 0.489362 (-3412 5358);
PAINT GREEN (-3412 5358);
FORCEPROP 2 LAST CDS_LIB mstr_standard
J 0
(-3350 5350);
DISPLAY 0.723404 (-3350 5350);
PAINT MONO (-3350 5350);
DISPLAY INVISIBLE (-3350 5350);
FORCEPROP 1 LAST BODY_TYPE PLUMBING
J 0
(-3350 5400);
DISPLAY 0.872340 (-3350 5400);
PAINT GREEN (-3350 5400);
DISPLAY INVISIBLE (-3350 5400);
FORCEPROP 1 LAST HDL_TAP TRUE
J 0
(-3025 5225);
DISPLAY 0.872340 (-3025 5225);
DISPLAY INVISIBLE (-3025 5225);
FORCEPROP 1 LAST PATH I171
J 0
(-3352 5350);
DISPLAY 0.872340 (-3352 5350);
PAINT GREEN (-3352 5350);
DISPLAY INVISIBLE (-3352 5350);
FORCEADD TAP..1
(-3350 5250);
FORCEPROP 3 LASTPIN (-3400 5250) SIG_NAME M_H_CPU1_SA_DQ<12>
J 0
(-3390 5260);
DISPLAY 0.659574 (-3390 5260);
PAINT MONO (-3390 5260);
DISPLAY INVISIBLE (-3390 5260);
FORCEPROP 1 LASTPIN (-3400 5250) BN 12
J 0
(-3412 5258);
DISPLAY 0.489362 (-3412 5258);
PAINT GREEN (-3412 5258);
FORCEPROP 2 LAST CDS_LIB mstr_standard
J 0
(-3350 5250);
DISPLAY 0.723404 (-3350 5250);
PAINT MONO (-3350 5250);
DISPLAY INVISIBLE (-3350 5250);
FORCEPROP 1 LAST BODY_TYPE PLUMBING
J 0
(-3350 5300);
DISPLAY 0.872340 (-3350 5300);
PAINT GREEN (-3350 5300);
DISPLAY INVISIBLE (-3350 5300);
FORCEPROP 1 LAST HDL_TAP TRUE
J 0
(-3025 5125);
DISPLAY 0.872340 (-3025 5125);
DISPLAY INVISIBLE (-3025 5125);
FORCEPROP 1 LAST PATH I172
J 0
(-3352 5250);
DISPLAY 0.872340 (-3352 5250);
PAINT GREEN (-3352 5250);
DISPLAY INVISIBLE (-3352 5250);
FORCEADD TAP..1
(-3350 5300);
FORCEPROP 3 LASTPIN (-3400 5300) SIG_NAME M_H_CPU1_SA_DQ<11>
J 0
(-3390 5310);
DISPLAY 0.659574 (-3390 5310);
PAINT MONO (-3390 5310);
DISPLAY INVISIBLE (-3390 5310);
FORCEPROP 1 LASTPIN (-3400 5300) BN 11
J 0
(-3412 5308);
DISPLAY 0.489362 (-3412 5308);
PAINT GREEN (-3412 5308);
FORCEPROP 2 LAST CDS_LIB mstr_standard
J 0
(-3350 5300);
DISPLAY 0.723404 (-3350 5300);
PAINT MONO (-3350 5300);
DISPLAY INVISIBLE (-3350 5300);
FORCEPROP 1 LAST BODY_TYPE PLUMBING
J 0
(-3350 5350);
DISPLAY 0.872340 (-3350 5350);
PAINT GREEN (-3350 5350);
DISPLAY INVISIBLE (-3350 5350);
FORCEPROP 1 LAST HDL_TAP TRUE
J 0
(-3025 5175);
DISPLAY 0.872340 (-3025 5175);
DISPLAY INVISIBLE (-3025 5175);
FORCEPROP 1 LAST PATH I173
J 0
(-3352 5300);
DISPLAY 0.872340 (-3352 5300);
PAINT GREEN (-3352 5300);
DISPLAY INVISIBLE (-3352 5300);
FORCEADD TAP..1
(-3350 5150);
FORCEPROP 3 LASTPIN (-3400 5150) SIG_NAME M_H_CPU1_SA_DQ<14>
J 0
(-3390 5160);
DISPLAY 0.659574 (-3390 5160);
PAINT MONO (-3390 5160);
DISPLAY INVISIBLE (-3390 5160);
FORCEPROP 1 LASTPIN (-3400 5150) BN 14
J 0
(-3412 5158);
DISPLAY 0.489362 (-3412 5158);
PAINT GREEN (-3412 5158);
FORCEPROP 2 LAST CDS_LIB mstr_standard
J 0
(-3350 5150);
DISPLAY 0.723404 (-3350 5150);
PAINT MONO (-3350 5150);
DISPLAY INVISIBLE (-3350 5150);
FORCEPROP 1 LAST BODY_TYPE PLUMBING
J 0
(-3350 5200);
DISPLAY 0.872340 (-3350 5200);
PAINT GREEN (-3350 5200);
DISPLAY INVISIBLE (-3350 5200);
FORCEPROP 1 LAST HDL_TAP TRUE
J 0
(-3025 5025);
DISPLAY 0.872340 (-3025 5025);
DISPLAY INVISIBLE (-3025 5025);
FORCEPROP 1 LAST PATH I174
J 0
(-3352 5150);
DISPLAY 0.872340 (-3352 5150);
PAINT GREEN (-3352 5150);
DISPLAY INVISIBLE (-3352 5150);
FORCEADD TAP..1
(-3350 5200);
FORCEPROP 3 LASTPIN (-3400 5200) SIG_NAME M_H_CPU1_SA_DQ<13>
J 0
(-3390 5210);
DISPLAY 0.659574 (-3390 5210);
PAINT MONO (-3390 5210);
DISPLAY INVISIBLE (-3390 5210);
FORCEPROP 1 LASTPIN (-3400 5200) BN 13
J 0
(-3412 5208);
DISPLAY 0.489362 (-3412 5208);
PAINT GREEN (-3412 5208);
FORCEPROP 2 LAST CDS_LIB mstr_standard
J 0
(-3350 5200);
DISPLAY 0.723404 (-3350 5200);
PAINT MONO (-3350 5200);
DISPLAY INVISIBLE (-3350 5200);
FORCEPROP 1 LAST BODY_TYPE PLUMBING
J 0
(-3350 5250);
DISPLAY 0.872340 (-3350 5250);
PAINT GREEN (-3350 5250);
DISPLAY INVISIBLE (-3350 5250);
FORCEPROP 1 LAST HDL_TAP TRUE
J 0
(-3025 5075);
DISPLAY 0.872340 (-3025 5075);
DISPLAY INVISIBLE (-3025 5075);
FORCEPROP 1 LAST PATH I175
J 0
(-3352 5200);
DISPLAY 0.872340 (-3352 5200);
PAINT GREEN (-3352 5200);
DISPLAY INVISIBLE (-3352 5200);
FORCEADD TAP..1
(-3350 5000);
FORCEPROP 3 LASTPIN (-3400 5000) SIG_NAME M_H_CPU1_SA_DQ<16>
J 0
(-3390 5010);
DISPLAY 0.659574 (-3390 5010);
PAINT MONO (-3390 5010);
DISPLAY INVISIBLE (-3390 5010);
FORCEPROP 1 LASTPIN (-3400 5000) BN 16
J 0
(-3412 5008);
DISPLAY 0.489362 (-3412 5008);
PAINT GREEN (-3412 5008);
FORCEPROP 2 LAST CDS_LIB mstr_standard
J 0
(-3350 5000);
DISPLAY 0.723404 (-3350 5000);
PAINT MONO (-3350 5000);
DISPLAY INVISIBLE (-3350 5000);
FORCEPROP 1 LAST BODY_TYPE PLUMBING
J 0
(-3350 5050);
DISPLAY 0.872340 (-3350 5050);
PAINT GREEN (-3350 5050);
DISPLAY INVISIBLE (-3350 5050);
FORCEPROP 1 LAST HDL_TAP TRUE
J 0
(-3025 4875);
DISPLAY 0.872340 (-3025 4875);
DISPLAY INVISIBLE (-3025 4875);
FORCEPROP 1 LAST PATH I176
J 0
(-3352 5000);
DISPLAY 0.872340 (-3352 5000);
PAINT GREEN (-3352 5000);
DISPLAY INVISIBLE (-3352 5000);
FORCEADD TAP..1
(-3350 5100);
FORCEPROP 3 LASTPIN (-3400 5100) SIG_NAME M_H_CPU1_SA_DQ<15>
J 0
(-3390 5110);
DISPLAY 0.659574 (-3390 5110);
PAINT MONO (-3390 5110);
DISPLAY INVISIBLE (-3390 5110);
FORCEPROP 1 LASTPIN (-3400 5100) BN 15
J 0
(-3412 5108);
DISPLAY 0.489362 (-3412 5108);
PAINT GREEN (-3412 5108);
FORCEPROP 2 LAST CDS_LIB mstr_standard
J 0
(-3350 5100);
DISPLAY 0.723404 (-3350 5100);
PAINT MONO (-3350 5100);
DISPLAY INVISIBLE (-3350 5100);
FORCEPROP 1 LAST BODY_TYPE PLUMBING
J 0
(-3350 5150);
DISPLAY 0.872340 (-3350 5150);
PAINT GREEN (-3350 5150);
DISPLAY INVISIBLE (-3350 5150);
FORCEPROP 1 LAST HDL_TAP TRUE
J 0
(-3025 4975);
DISPLAY 0.872340 (-3025 4975);
DISPLAY INVISIBLE (-3025 4975);
FORCEPROP 1 LAST PATH I177
J 0
(-3352 5100);
DISPLAY 0.872340 (-3352 5100);
PAINT GREEN (-3352 5100);
DISPLAY INVISIBLE (-3352 5100);
FORCEADD TAP..1
(-3350 4900);
FORCEPROP 3 LASTPIN (-3400 4900) SIG_NAME M_H_CPU1_SA_DQ<18>
J 0
(-3390 4910);
DISPLAY 0.659574 (-3390 4910);
PAINT MONO (-3390 4910);
DISPLAY INVISIBLE (-3390 4910);
FORCEPROP 1 LASTPIN (-3400 4900) BN 18
J 0
(-3412 4908);
DISPLAY 0.489362 (-3412 4908);
PAINT GREEN (-3412 4908);
FORCEPROP 2 LAST CDS_LIB mstr_standard
J 0
(-3350 4900);
DISPLAY 0.723404 (-3350 4900);
PAINT MONO (-3350 4900);
DISPLAY INVISIBLE (-3350 4900);
FORCEPROP 1 LAST BODY_TYPE PLUMBING
J 0
(-3350 4950);
DISPLAY 0.872340 (-3350 4950);
PAINT GREEN (-3350 4950);
DISPLAY INVISIBLE (-3350 4950);
FORCEPROP 1 LAST HDL_TAP TRUE
J 0
(-3025 4775);
DISPLAY 0.872340 (-3025 4775);
DISPLAY INVISIBLE (-3025 4775);
FORCEPROP 1 LAST PATH I178
J 0
(-3352 4900);
DISPLAY 0.872340 (-3352 4900);
PAINT GREEN (-3352 4900);
DISPLAY INVISIBLE (-3352 4900);
FORCEADD TAP..1
(-3350 4950);
FORCEPROP 3 LASTPIN (-3400 4950) SIG_NAME M_H_CPU1_SA_DQ<17>
J 0
(-3390 4960);
DISPLAY 0.659574 (-3390 4960);
PAINT MONO (-3390 4960);
DISPLAY INVISIBLE (-3390 4960);
FORCEPROP 1 LASTPIN (-3400 4950) BN 17
J 0
(-3412 4958);
DISPLAY 0.489362 (-3412 4958);
PAINT GREEN (-3412 4958);
FORCEPROP 2 LAST CDS_LIB mstr_standard
J 0
(-3350 4950);
DISPLAY 0.723404 (-3350 4950);
PAINT MONO (-3350 4950);
DISPLAY INVISIBLE (-3350 4950);
FORCEPROP 1 LAST BODY_TYPE PLUMBING
J 0
(-3350 5000);
DISPLAY 0.872340 (-3350 5000);
PAINT GREEN (-3350 5000);
DISPLAY INVISIBLE (-3350 5000);
FORCEPROP 1 LAST HDL_TAP TRUE
J 0
(-3025 4825);
DISPLAY 0.872340 (-3025 4825);
DISPLAY INVISIBLE (-3025 4825);
FORCEPROP 1 LAST PATH I179
J 0
(-3352 4950);
DISPLAY 0.872340 (-3352 4950);
PAINT GREEN (-3352 4950);
DISPLAY INVISIBLE (-3352 4950);
FORCEADD TAP..1
(-3350 4800);
FORCEPROP 3 LASTPIN (-3400 4800) SIG_NAME M_H_CPU1_SA_DQ<20>
J 0
(-3390 4810);
DISPLAY 0.659574 (-3390 4810);
PAINT MONO (-3390 4810);
DISPLAY INVISIBLE (-3390 4810);
FORCEPROP 1 LASTPIN (-3400 4800) BN 20
J 0
(-3412 4808);
DISPLAY 0.489362 (-3412 4808);
PAINT GREEN (-3412 4808);
FORCEPROP 2 LAST CDS_LIB mstr_standard
J 0
(-3350 4800);
DISPLAY 0.723404 (-3350 4800);
PAINT MONO (-3350 4800);
DISPLAY INVISIBLE (-3350 4800);
FORCEPROP 1 LAST BODY_TYPE PLUMBING
J 0
(-3350 4850);
DISPLAY 0.872340 (-3350 4850);
PAINT GREEN (-3350 4850);
DISPLAY INVISIBLE (-3350 4850);
FORCEPROP 1 LAST HDL_TAP TRUE
J 0
(-3025 4675);
DISPLAY 0.872340 (-3025 4675);
DISPLAY INVISIBLE (-3025 4675);
FORCEPROP 1 LAST PATH I180
J 0
(-3352 4800);
DISPLAY 0.872340 (-3352 4800);
PAINT GREEN (-3352 4800);
DISPLAY INVISIBLE (-3352 4800);
FORCEADD TAP..1
(-3350 4850);
FORCEPROP 3 LASTPIN (-3400 4850) SIG_NAME M_H_CPU1_SA_DQ<19>
J 0
(-3390 4860);
DISPLAY 0.659574 (-3390 4860);
PAINT MONO (-3390 4860);
DISPLAY INVISIBLE (-3390 4860);
FORCEPROP 1 LASTPIN (-3400 4850) BN 19
J 0
(-3412 4858);
DISPLAY 0.489362 (-3412 4858);
PAINT GREEN (-3412 4858);
FORCEPROP 2 LAST CDS_LIB mstr_standard
J 0
(-3350 4850);
DISPLAY 0.723404 (-3350 4850);
PAINT MONO (-3350 4850);
DISPLAY INVISIBLE (-3350 4850);
FORCEPROP 1 LAST BODY_TYPE PLUMBING
J 0
(-3350 4900);
DISPLAY 0.872340 (-3350 4900);
PAINT GREEN (-3350 4900);
DISPLAY INVISIBLE (-3350 4900);
FORCEPROP 1 LAST HDL_TAP TRUE
J 0
(-3025 4725);
DISPLAY 0.872340 (-3025 4725);
DISPLAY INVISIBLE (-3025 4725);
FORCEPROP 1 LAST PATH I181
J 0
(-3352 4850);
DISPLAY 0.872340 (-3352 4850);
PAINT GREEN (-3352 4850);
DISPLAY INVISIBLE (-3352 4850);
FORCEADD TAP..1
(-3350 4750);
FORCEPROP 3 LASTPIN (-3400 4750) SIG_NAME M_H_CPU1_SA_DQ<21>
J 0
(-3390 4760);
DISPLAY 0.659574 (-3390 4760);
PAINT MONO (-3390 4760);
DISPLAY INVISIBLE (-3390 4760);
FORCEPROP 1 LASTPIN (-3400 4750) BN 21
J 0
(-3412 4758);
DISPLAY 0.489362 (-3412 4758);
PAINT GREEN (-3412 4758);
FORCEPROP 2 LAST CDS_LIB mstr_standard
J 0
(-3350 4750);
DISPLAY 0.723404 (-3350 4750);
PAINT MONO (-3350 4750);
DISPLAY INVISIBLE (-3350 4750);
FORCEPROP 1 LAST BODY_TYPE PLUMBING
J 0
(-3350 4800);
DISPLAY 0.872340 (-3350 4800);
PAINT GREEN (-3350 4800);
DISPLAY INVISIBLE (-3350 4800);
FORCEPROP 1 LAST HDL_TAP TRUE
J 0
(-3025 4625);
DISPLAY 0.872340 (-3025 4625);
DISPLAY INVISIBLE (-3025 4625);
FORCEPROP 1 LAST PATH I182
J 0
(-3352 4750);
DISPLAY 0.872340 (-3352 4750);
PAINT GREEN (-3352 4750);
DISPLAY INVISIBLE (-3352 4750);
FORCEADD TAP..1
(-3350 4650);
FORCEPROP 3 LASTPIN (-3400 4650) SIG_NAME M_H_CPU1_SA_DQ<23>
J 0
(-3390 4660);
DISPLAY 0.659574 (-3390 4660);
PAINT MONO (-3390 4660);
DISPLAY INVISIBLE (-3390 4660);
FORCEPROP 1 LASTPIN (-3400 4650) BN 23
J 0
(-3412 4658);
DISPLAY 0.489362 (-3412 4658);
PAINT GREEN (-3412 4658);
FORCEPROP 2 LAST CDS_LIB mstr_standard
J 0
(-3350 4650);
DISPLAY 0.723404 (-3350 4650);
PAINT MONO (-3350 4650);
DISPLAY INVISIBLE (-3350 4650);
FORCEPROP 1 LAST BODY_TYPE PLUMBING
J 0
(-3350 4700);
DISPLAY 0.872340 (-3350 4700);
PAINT GREEN (-3350 4700);
DISPLAY INVISIBLE (-3350 4700);
FORCEPROP 1 LAST HDL_TAP TRUE
J 0
(-3025 4525);
DISPLAY 0.872340 (-3025 4525);
DISPLAY INVISIBLE (-3025 4525);
FORCEPROP 1 LAST PATH I183
J 0
(-3352 4650);
DISPLAY 0.872340 (-3352 4650);
PAINT GREEN (-3352 4650);
DISPLAY INVISIBLE (-3352 4650);
FORCEADD TAP..1
(-3350 4700);
FORCEPROP 3 LASTPIN (-3400 4700) SIG_NAME M_H_CPU1_SA_DQ<22>
J 0
(-3390 4710);
DISPLAY 0.659574 (-3390 4710);
PAINT MONO (-3390 4710);
DISPLAY INVISIBLE (-3390 4710);
FORCEPROP 1 LASTPIN (-3400 4700) BN 22
J 0
(-3412 4708);
DISPLAY 0.489362 (-3412 4708);
PAINT GREEN (-3412 4708);
FORCEPROP 2 LAST CDS_LIB mstr_standard
J 0
(-3350 4700);
DISPLAY 0.723404 (-3350 4700);
PAINT MONO (-3350 4700);
DISPLAY INVISIBLE (-3350 4700);
FORCEPROP 1 LAST BODY_TYPE PLUMBING
J 0
(-3350 4750);
DISPLAY 0.872340 (-3350 4750);
PAINT GREEN (-3350 4750);
DISPLAY INVISIBLE (-3350 4750);
FORCEPROP 1 LAST HDL_TAP TRUE
J 0
(-3025 4575);
DISPLAY 0.872340 (-3025 4575);
DISPLAY INVISIBLE (-3025 4575);
FORCEPROP 1 LAST PATH I184
J 0
(-3352 4700);
DISPLAY 0.872340 (-3352 4700);
PAINT GREEN (-3352 4700);
DISPLAY INVISIBLE (-3352 4700);
FORCEADD TAP..1
(-3350 4550);
FORCEPROP 3 LASTPIN (-3400 4550) SIG_NAME M_H_CPU1_SA_DQ<24>
J 0
(-3390 4560);
DISPLAY 0.659574 (-3390 4560);
PAINT MONO (-3390 4560);
DISPLAY INVISIBLE (-3390 4560);
FORCEPROP 1 LASTPIN (-3400 4550) BN 24
J 0
(-3412 4558);
DISPLAY 0.489362 (-3412 4558);
PAINT GREEN (-3412 4558);
FORCEPROP 2 LAST CDS_LIB mstr_standard
J 0
(-3350 4550);
DISPLAY 0.723404 (-3350 4550);
PAINT MONO (-3350 4550);
DISPLAY INVISIBLE (-3350 4550);
FORCEPROP 1 LAST BODY_TYPE PLUMBING
J 0
(-3350 4600);
DISPLAY 0.872340 (-3350 4600);
PAINT GREEN (-3350 4600);
DISPLAY INVISIBLE (-3350 4600);
FORCEPROP 1 LAST HDL_TAP TRUE
J 0
(-3025 4425);
DISPLAY 0.872340 (-3025 4425);
DISPLAY INVISIBLE (-3025 4425);
FORCEPROP 1 LAST PATH I185
J 0
(-3352 4550);
DISPLAY 0.872340 (-3352 4550);
PAINT GREEN (-3352 4550);
DISPLAY INVISIBLE (-3352 4550);
FORCEADD TAP..1
(-3350 4500);
FORCEPROP 3 LASTPIN (-3400 4500) SIG_NAME M_H_CPU1_SA_DQ<25>
J 0
(-3390 4510);
DISPLAY 0.659574 (-3390 4510);
PAINT MONO (-3390 4510);
DISPLAY INVISIBLE (-3390 4510);
FORCEPROP 1 LASTPIN (-3400 4500) BN 25
J 0
(-3412 4508);
DISPLAY 0.489362 (-3412 4508);
PAINT GREEN (-3412 4508);
FORCEPROP 2 LAST CDS_LIB mstr_standard
J 0
(-3350 4500);
DISPLAY 0.723404 (-3350 4500);
PAINT MONO (-3350 4500);
DISPLAY INVISIBLE (-3350 4500);
FORCEPROP 1 LAST BODY_TYPE PLUMBING
J 0
(-3350 4550);
DISPLAY 0.872340 (-3350 4550);
PAINT GREEN (-3350 4550);
DISPLAY INVISIBLE (-3350 4550);
FORCEPROP 1 LAST HDL_TAP TRUE
J 0
(-3025 4375);
DISPLAY 0.872340 (-3025 4375);
DISPLAY INVISIBLE (-3025 4375);
FORCEPROP 1 LAST PATH I186
J 0
(-3352 4500);
DISPLAY 0.872340 (-3352 4500);
PAINT GREEN (-3352 4500);
DISPLAY INVISIBLE (-3352 4500);
FORCEADD TAP..1
(-3350 4400);
FORCEPROP 3 LASTPIN (-3400 4400) SIG_NAME M_H_CPU1_SA_DQ<27>
J 0
(-3390 4410);
DISPLAY 0.659574 (-3390 4410);
PAINT MONO (-3390 4410);
DISPLAY INVISIBLE (-3390 4410);
FORCEPROP 1 LASTPIN (-3400 4400) BN 27
J 0
(-3412 4408);
DISPLAY 0.489362 (-3412 4408);
PAINT GREEN (-3412 4408);
FORCEPROP 2 LAST CDS_LIB mstr_standard
J 0
(-3350 4400);
DISPLAY 0.723404 (-3350 4400);
PAINT MONO (-3350 4400);
DISPLAY INVISIBLE (-3350 4400);
FORCEPROP 1 LAST BODY_TYPE PLUMBING
J 0
(-3350 4450);
DISPLAY 0.872340 (-3350 4450);
PAINT GREEN (-3350 4450);
DISPLAY INVISIBLE (-3350 4450);
FORCEPROP 1 LAST HDL_TAP TRUE
J 0
(-3025 4275);
DISPLAY 0.872340 (-3025 4275);
DISPLAY INVISIBLE (-3025 4275);
FORCEPROP 1 LAST PATH I187
J 0
(-3352 4400);
DISPLAY 0.872340 (-3352 4400);
PAINT GREEN (-3352 4400);
DISPLAY INVISIBLE (-3352 4400);
FORCEADD TAP..1
(-3350 4450);
FORCEPROP 3 LASTPIN (-3400 4450) SIG_NAME M_H_CPU1_SA_DQ<26>
J 0
(-3390 4460);
DISPLAY 0.659574 (-3390 4460);
PAINT MONO (-3390 4460);
DISPLAY INVISIBLE (-3390 4460);
FORCEPROP 1 LASTPIN (-3400 4450) BN 26
J 0
(-3412 4458);
DISPLAY 0.489362 (-3412 4458);
PAINT GREEN (-3412 4458);
FORCEPROP 2 LAST CDS_LIB mstr_standard
J 0
(-3350 4450);
DISPLAY 0.723404 (-3350 4450);
PAINT MONO (-3350 4450);
DISPLAY INVISIBLE (-3350 4450);
FORCEPROP 1 LAST BODY_TYPE PLUMBING
J 0
(-3350 4500);
DISPLAY 0.872340 (-3350 4500);
PAINT GREEN (-3350 4500);
DISPLAY INVISIBLE (-3350 4500);
FORCEPROP 1 LAST HDL_TAP TRUE
J 0
(-3025 4325);
DISPLAY 0.872340 (-3025 4325);
DISPLAY INVISIBLE (-3025 4325);
FORCEPROP 1 LAST PATH I188
J 0
(-3352 4450);
DISPLAY 0.872340 (-3352 4450);
PAINT GREEN (-3352 4450);
DISPLAY INVISIBLE (-3352 4450);
FORCEADD TAP..1
(-3350 4300);
FORCEPROP 3 LASTPIN (-3400 4300) SIG_NAME M_H_CPU1_SA_DQ<29>
J 0
(-3390 4310);
DISPLAY 0.659574 (-3390 4310);
PAINT MONO (-3390 4310);
DISPLAY INVISIBLE (-3390 4310);
FORCEPROP 1 LASTPIN (-3400 4300) BN 29
J 0
(-3412 4308);
DISPLAY 0.489362 (-3412 4308);
PAINT GREEN (-3412 4308);
FORCEPROP 2 LAST CDS_LIB mstr_standard
J 0
(-3350 4300);
DISPLAY 0.723404 (-3350 4300);
PAINT MONO (-3350 4300);
DISPLAY INVISIBLE (-3350 4300);
FORCEPROP 1 LAST BODY_TYPE PLUMBING
J 0
(-3350 4350);
DISPLAY 0.872340 (-3350 4350);
PAINT GREEN (-3350 4350);
DISPLAY INVISIBLE (-3350 4350);
FORCEPROP 1 LAST HDL_TAP TRUE
J 0
(-3025 4175);
DISPLAY 0.872340 (-3025 4175);
DISPLAY INVISIBLE (-3025 4175);
FORCEPROP 1 LAST PATH I189
J 0
(-3352 4300);
DISPLAY 0.872340 (-3352 4300);
PAINT GREEN (-3352 4300);
DISPLAY INVISIBLE (-3352 4300);
FORCEADD TAP..1
(-3350 4350);
FORCEPROP 3 LASTPIN (-3400 4350) SIG_NAME M_H_CPU1_SA_DQ<28>
J 0
(-3390 4360);
DISPLAY 0.659574 (-3390 4360);
PAINT MONO (-3390 4360);
DISPLAY INVISIBLE (-3390 4360);
FORCEPROP 1 LASTPIN (-3400 4350) BN 28
J 0
(-3412 4358);
DISPLAY 0.489362 (-3412 4358);
PAINT GREEN (-3412 4358);
FORCEPROP 2 LAST CDS_LIB mstr_standard
J 0
(-3350 4350);
DISPLAY 0.723404 (-3350 4350);
PAINT MONO (-3350 4350);
DISPLAY INVISIBLE (-3350 4350);
FORCEPROP 1 LAST BODY_TYPE PLUMBING
J 0
(-3350 4400);
DISPLAY 0.872340 (-3350 4400);
PAINT GREEN (-3350 4400);
DISPLAY INVISIBLE (-3350 4400);
FORCEPROP 1 LAST HDL_TAP TRUE
J 0
(-3025 4225);
DISPLAY 0.872340 (-3025 4225);
DISPLAY INVISIBLE (-3025 4225);
FORCEPROP 1 LAST PATH I190
J 0
(-3352 4350);
DISPLAY 0.872340 (-3352 4350);
PAINT GREEN (-3352 4350);
DISPLAY INVISIBLE (-3352 4350);
FORCEADD TAP..1
(-3350 4250);
FORCEPROP 3 LASTPIN (-3400 4250) SIG_NAME M_H_CPU1_SA_DQ<30>
J 0
(-3390 4260);
DISPLAY 0.659574 (-3390 4260);
PAINT MONO (-3390 4260);
DISPLAY INVISIBLE (-3390 4260);
FORCEPROP 1 LASTPIN (-3400 4250) BN 30
J 0
(-3412 4258);
DISPLAY 0.489362 (-3412 4258);
PAINT GREEN (-3412 4258);
FORCEPROP 2 LAST CDS_LIB mstr_standard
J 0
(-3350 4250);
DISPLAY 0.723404 (-3350 4250);
PAINT MONO (-3350 4250);
DISPLAY INVISIBLE (-3350 4250);
FORCEPROP 1 LAST BODY_TYPE PLUMBING
J 0
(-3350 4300);
DISPLAY 0.872340 (-3350 4300);
PAINT GREEN (-3350 4300);
DISPLAY INVISIBLE (-3350 4300);
FORCEPROP 1 LAST HDL_TAP TRUE
J 0
(-3025 4125);
DISPLAY 0.872340 (-3025 4125);
DISPLAY INVISIBLE (-3025 4125);
FORCEPROP 1 LAST PATH I191
J 0
(-3352 4250);
DISPLAY 0.872340 (-3352 4250);
PAINT GREEN (-3352 4250);
DISPLAY INVISIBLE (-3352 4250);
FORCEADD TAP..1
(-3350 4100);
FORCEPROP 3 LASTPIN (-3400 4100) SIG_NAME M_H_CPU1_SB_DQ<0>
J 0
(-3390 4110);
DISPLAY 0.659574 (-3390 4110);
PAINT MONO (-3390 4110);
DISPLAY INVISIBLE (-3390 4110);
FORCEPROP 1 LASTPIN (-3400 4100) BN 0
J 0
(-3412 4108);
DISPLAY 0.489362 (-3412 4108);
PAINT GREEN (-3412 4108);
FORCEPROP 2 LAST CDS_LIB mstr_standard
J 0
(-3350 4100);
DISPLAY 0.723404 (-3350 4100);
PAINT MONO (-3350 4100);
DISPLAY INVISIBLE (-3350 4100);
FORCEPROP 1 LAST BODY_TYPE PLUMBING
J 0
(-3350 4150);
DISPLAY 0.872340 (-3350 4150);
PAINT GREEN (-3350 4150);
DISPLAY INVISIBLE (-3350 4150);
FORCEPROP 1 LAST HDL_TAP TRUE
J 0
(-3025 3975);
DISPLAY 0.872340 (-3025 3975);
DISPLAY INVISIBLE (-3025 3975);
FORCEPROP 1 LAST PATH I192
J 0
(-3352 4100);
DISPLAY 0.872340 (-3352 4100);
PAINT GREEN (-3352 4100);
DISPLAY INVISIBLE (-3352 4100);
FORCEADD TAP..1
(-3350 4200);
FORCEPROP 3 LASTPIN (-3400 4200) SIG_NAME M_H_CPU1_SA_DQ<31>
J 0
(-3390 4210);
DISPLAY 0.659574 (-3390 4210);
PAINT MONO (-3390 4210);
DISPLAY INVISIBLE (-3390 4210);
FORCEPROP 1 LASTPIN (-3400 4200) BN 31
J 0
(-3412 4208);
DISPLAY 0.489362 (-3412 4208);
PAINT GREEN (-3412 4208);
FORCEPROP 2 LAST CDS_LIB mstr_standard
J 0
(-3350 4200);
DISPLAY 0.723404 (-3350 4200);
PAINT MONO (-3350 4200);
DISPLAY INVISIBLE (-3350 4200);
FORCEPROP 1 LAST BODY_TYPE PLUMBING
J 0
(-3350 4250);
DISPLAY 0.872340 (-3350 4250);
PAINT GREEN (-3350 4250);
DISPLAY INVISIBLE (-3350 4250);
FORCEPROP 1 LAST HDL_TAP TRUE
J 0
(-3025 4075);
DISPLAY 0.872340 (-3025 4075);
DISPLAY INVISIBLE (-3025 4075);
FORCEPROP 1 LAST PATH I193
J 0
(-3352 4200);
DISPLAY 0.872340 (-3352 4200);
PAINT GREEN (-3352 4200);
DISPLAY INVISIBLE (-3352 4200);
FORCEADD OFFPAGE..3
(-2625 4125);
FORCEPROP 2 LAST $XR0 105 
J 0
(-2411 4125);
DISPLAY 0.638298 (-2411 4125);
PAINT MONO (-2411 4125);
FORCEPROP 2 LAST CDS_LIB mstr_standard
J 0
(-2625 4125);
DISPLAY 0.723404 (-2625 4125);
PAINT MONO (-2625 4125);
DISPLAY INVISIBLE (-2625 4125);
FORCEPROP 1 LAST OFFPAGE TRUE
J 0
(-2300 4000);
DISPLAY 0.872340 (-2300 4000);
PAINT GREEN (-2300 4000);
DISPLAY INVISIBLE (-2300 4000);
FORCEPROP 1 LAST COMMENT_BODY TRUE
J 0
(-2675 4025);
DISPLAY 0.872340 (-2675 4025);
PAINT GREEN (-2675 4025);
DISPLAY INVISIBLE (-2675 4025);
FORCEPROP 2 LAST PATH I194
J 0
(-2400 4175);
DISPLAY 1.021277 (-2400 4175);
DISPLAY INVISIBLE (-2400 4175);
FORCEADD OFFPAGE..6
R 2
(-2750 2350);
FORCEPROP 2 LAST $XR0 105 
J 0
(-2536 2350);
DISPLAY 0.638298 (-2536 2350);
PAINT MONO (-2536 2350);
FORCEPROP 2 LAST CDS_LIB mstr_standard
J 2
(-2750 2350);
DISPLAY 0.723404 (-2750 2350);
PAINT MONO (-2750 2350);
DISPLAY INVISIBLE (-2750 2350);
FORCEPROP 1 LAST OFFPAGE TRUE
J 2
(-3075 2225);
DISPLAY 0.872340 (-3075 2225);
PAINT GREEN (-3075 2225);
DISPLAY INVISIBLE (-3075 2225);
FORCEPROP 1 LAST COMMENT_BODY TRUE
J 2
(-2850 2275);
DISPLAY 0.872340 (-2850 2275);
PAINT GREEN (-2850 2275);
DISPLAY INVISIBLE (-2850 2275);
FORCEPROP 2 LAST PATH I195
J 0
(-2525 2400);
DISPLAY 1.021277 (-2525 2400);
DISPLAY INVISIBLE (-2525 2400);
FORCEADD TAP..1
(-3350 4000);
FORCEPROP 3 LASTPIN (-3400 4000) SIG_NAME M_H_CPU1_SB_DQ<2>
J 0
(-3390 4010);
DISPLAY 0.659574 (-3390 4010);
PAINT MONO (-3390 4010);
DISPLAY INVISIBLE (-3390 4010);
FORCEPROP 1 LASTPIN (-3400 4000) BN 2
J 0
(-3412 4008);
DISPLAY 0.489362 (-3412 4008);
PAINT GREEN (-3412 4008);
FORCEPROP 2 LAST CDS_LIB mstr_standard
J 0
(-3350 4000);
DISPLAY 0.723404 (-3350 4000);
PAINT MONO (-3350 4000);
DISPLAY INVISIBLE (-3350 4000);
FORCEPROP 1 LAST BODY_TYPE PLUMBING
J 0
(-3350 4050);
DISPLAY 0.872340 (-3350 4050);
PAINT GREEN (-3350 4050);
DISPLAY INVISIBLE (-3350 4050);
FORCEPROP 1 LAST HDL_TAP TRUE
J 0
(-3025 3875);
DISPLAY 0.872340 (-3025 3875);
DISPLAY INVISIBLE (-3025 3875);
FORCEPROP 1 LAST PATH I196
J 0
(-3352 4000);
DISPLAY 0.872340 (-3352 4000);
PAINT GREEN (-3352 4000);
DISPLAY INVISIBLE (-3352 4000);
FORCEADD TAP..1
(-3350 4050);
FORCEPROP 3 LASTPIN (-3400 4050) SIG_NAME M_H_CPU1_SB_DQ<1>
J 0
(-3390 4060);
DISPLAY 0.659574 (-3390 4060);
PAINT MONO (-3390 4060);
DISPLAY INVISIBLE (-3390 4060);
FORCEPROP 1 LASTPIN (-3400 4050) BN 1
J 0
(-3412 4058);
DISPLAY 0.489362 (-3412 4058);
PAINT GREEN (-3412 4058);
FORCEPROP 2 LAST CDS_LIB mstr_standard
J 0
(-3350 4050);
DISPLAY 0.723404 (-3350 4050);
PAINT MONO (-3350 4050);
DISPLAY INVISIBLE (-3350 4050);
FORCEPROP 1 LAST BODY_TYPE PLUMBING
J 0
(-3350 4100);
DISPLAY 0.872340 (-3350 4100);
PAINT GREEN (-3350 4100);
DISPLAY INVISIBLE (-3350 4100);
FORCEPROP 1 LAST HDL_TAP TRUE
J 0
(-3025 3925);
DISPLAY 0.872340 (-3025 3925);
DISPLAY INVISIBLE (-3025 3925);
FORCEPROP 1 LAST PATH I197
J 0
(-3352 4050);
DISPLAY 0.872340 (-3352 4050);
PAINT GREEN (-3352 4050);
DISPLAY INVISIBLE (-3352 4050);
FORCEADD TAP..1
(-3350 3950);
FORCEPROP 3 LASTPIN (-3400 3950) SIG_NAME M_H_CPU1_SB_DQ<3>
J 0
(-3390 3960);
DISPLAY 0.659574 (-3390 3960);
PAINT MONO (-3390 3960);
DISPLAY INVISIBLE (-3390 3960);
FORCEPROP 1 LASTPIN (-3400 3950) BN 3
J 0
(-3412 3958);
DISPLAY 0.489362 (-3412 3958);
PAINT GREEN (-3412 3958);
FORCEPROP 2 LAST CDS_LIB mstr_standard
J 0
(-3350 3950);
DISPLAY 0.723404 (-3350 3950);
PAINT MONO (-3350 3950);
DISPLAY INVISIBLE (-3350 3950);
FORCEPROP 1 LAST BODY_TYPE PLUMBING
J 0
(-3350 4000);
DISPLAY 0.872340 (-3350 4000);
PAINT GREEN (-3350 4000);
DISPLAY INVISIBLE (-3350 4000);
FORCEPROP 1 LAST HDL_TAP TRUE
J 0
(-3025 3825);
DISPLAY 0.872340 (-3025 3825);
DISPLAY INVISIBLE (-3025 3825);
FORCEPROP 1 LAST PATH I198
J 0
(-3352 3950);
DISPLAY 0.872340 (-3352 3950);
PAINT GREEN (-3352 3950);
DISPLAY INVISIBLE (-3352 3950);
FORCEADD TAP..1
(-3350 3900);
FORCEPROP 3 LASTPIN (-3400 3900) SIG_NAME M_H_CPU1_SB_DQ<4>
J 0
(-3390 3910);
DISPLAY 0.659574 (-3390 3910);
PAINT MONO (-3390 3910);
DISPLAY INVISIBLE (-3390 3910);
FORCEPROP 1 LASTPIN (-3400 3900) BN 4
J 0
(-3412 3908);
DISPLAY 0.489362 (-3412 3908);
PAINT GREEN (-3412 3908);
FORCEPROP 2 LAST CDS_LIB mstr_standard
J 0
(-3350 3900);
DISPLAY 0.723404 (-3350 3900);
PAINT MONO (-3350 3900);
DISPLAY INVISIBLE (-3350 3900);
FORCEPROP 1 LAST BODY_TYPE PLUMBING
J 0
(-3350 3950);
DISPLAY 0.872340 (-3350 3950);
PAINT GREEN (-3350 3950);
DISPLAY INVISIBLE (-3350 3950);
FORCEPROP 1 LAST HDL_TAP TRUE
J 0
(-3025 3775);
DISPLAY 0.872340 (-3025 3775);
DISPLAY INVISIBLE (-3025 3775);
FORCEPROP 1 LAST PATH I199
J 0
(-3352 3900);
DISPLAY 0.872340 (-3352 3900);
PAINT GREEN (-3352 3900);
DISPLAY INVISIBLE (-3352 3900);
FORCEADD TAP..1
(-3350 3850);
FORCEPROP 3 LASTPIN (-3400 3850) SIG_NAME M_H_CPU1_SB_DQ<5>
J 0
(-3390 3860);
DISPLAY 0.659574 (-3390 3860);
PAINT MONO (-3390 3860);
DISPLAY INVISIBLE (-3390 3860);
FORCEPROP 1 LASTPIN (-3400 3850) BN 5
J 0
(-3412 3858);
DISPLAY 0.489362 (-3412 3858);
PAINT GREEN (-3412 3858);
FORCEPROP 2 LAST CDS_LIB mstr_standard
J 0
(-3350 3850);
DISPLAY 0.723404 (-3350 3850);
PAINT MONO (-3350 3850);
DISPLAY INVISIBLE (-3350 3850);
FORCEPROP 1 LAST BODY_TYPE PLUMBING
J 0
(-3350 3900);
DISPLAY 0.872340 (-3350 3900);
PAINT GREEN (-3350 3900);
DISPLAY INVISIBLE (-3350 3900);
FORCEPROP 1 LAST HDL_TAP TRUE
J 0
(-3025 3725);
DISPLAY 0.872340 (-3025 3725);
DISPLAY INVISIBLE (-3025 3725);
FORCEPROP 1 LAST PATH I200
J 0
(-3352 3850);
DISPLAY 0.872340 (-3352 3850);
PAINT GREEN (-3352 3850);
DISPLAY INVISIBLE (-3352 3850);
FORCEADD TAP..1
(-3350 3750);
FORCEPROP 3 LASTPIN (-3400 3750) SIG_NAME M_H_CPU1_SB_DQ<7>
J 0
(-3390 3760);
DISPLAY 0.659574 (-3390 3760);
PAINT MONO (-3390 3760);
DISPLAY INVISIBLE (-3390 3760);
FORCEPROP 1 LASTPIN (-3400 3750) BN 7
J 0
(-3412 3758);
DISPLAY 0.489362 (-3412 3758);
PAINT GREEN (-3412 3758);
FORCEPROP 2 LAST CDS_LIB mstr_standard
J 0
(-3350 3750);
DISPLAY 0.723404 (-3350 3750);
PAINT MONO (-3350 3750);
DISPLAY INVISIBLE (-3350 3750);
FORCEPROP 1 LAST BODY_TYPE PLUMBING
J 0
(-3350 3800);
DISPLAY 0.872340 (-3350 3800);
PAINT GREEN (-3350 3800);
DISPLAY INVISIBLE (-3350 3800);
FORCEPROP 1 LAST HDL_TAP TRUE
J 0
(-3025 3625);
DISPLAY 0.872340 (-3025 3625);
DISPLAY INVISIBLE (-3025 3625);
FORCEPROP 1 LAST PATH I201
J 0
(-3352 3750);
DISPLAY 0.872340 (-3352 3750);
PAINT GREEN (-3352 3750);
DISPLAY INVISIBLE (-3352 3750);
FORCEADD TAP..1
(-3350 3650);
FORCEPROP 3 LASTPIN (-3400 3650) SIG_NAME M_H_CPU1_SB_DQ<8>
J 0
(-3390 3660);
DISPLAY 0.659574 (-3390 3660);
PAINT MONO (-3390 3660);
DISPLAY INVISIBLE (-3390 3660);
FORCEPROP 1 LASTPIN (-3400 3650) BN 8
J 0
(-3412 3658);
DISPLAY 0.489362 (-3412 3658);
PAINT GREEN (-3412 3658);
FORCEPROP 2 LAST CDS_LIB mstr_standard
J 0
(-3350 3650);
DISPLAY 0.723404 (-3350 3650);
PAINT MONO (-3350 3650);
DISPLAY INVISIBLE (-3350 3650);
FORCEPROP 1 LAST BODY_TYPE PLUMBING
J 0
(-3350 3700);
DISPLAY 0.872340 (-3350 3700);
PAINT GREEN (-3350 3700);
DISPLAY INVISIBLE (-3350 3700);
FORCEPROP 1 LAST HDL_TAP TRUE
J 0
(-3025 3525);
DISPLAY 0.872340 (-3025 3525);
DISPLAY INVISIBLE (-3025 3525);
FORCEPROP 1 LAST PATH I202
J 0
(-3352 3650);
DISPLAY 0.872340 (-3352 3650);
PAINT GREEN (-3352 3650);
DISPLAY INVISIBLE (-3352 3650);
FORCEADD TAP..1
(-3350 3800);
FORCEPROP 3 LASTPIN (-3400 3800) SIG_NAME M_H_CPU1_SB_DQ<6>
J 0
(-3390 3810);
DISPLAY 0.659574 (-3390 3810);
PAINT MONO (-3390 3810);
DISPLAY INVISIBLE (-3390 3810);
FORCEPROP 1 LASTPIN (-3400 3800) BN 6
J 0
(-3412 3808);
DISPLAY 0.489362 (-3412 3808);
PAINT GREEN (-3412 3808);
FORCEPROP 2 LAST CDS_LIB mstr_standard
J 0
(-3350 3800);
DISPLAY 0.723404 (-3350 3800);
PAINT MONO (-3350 3800);
DISPLAY INVISIBLE (-3350 3800);
FORCEPROP 1 LAST BODY_TYPE PLUMBING
J 0
(-3350 3850);
DISPLAY 0.872340 (-3350 3850);
PAINT GREEN (-3350 3850);
DISPLAY INVISIBLE (-3350 3850);
FORCEPROP 1 LAST HDL_TAP TRUE
J 0
(-3025 3675);
DISPLAY 0.872340 (-3025 3675);
DISPLAY INVISIBLE (-3025 3675);
FORCEPROP 1 LAST PATH I203
J 0
(-3352 3800);
DISPLAY 0.872340 (-3352 3800);
PAINT GREEN (-3352 3800);
DISPLAY INVISIBLE (-3352 3800);
FORCEADD TAP..1
(-3350 3600);
FORCEPROP 3 LASTPIN (-3400 3600) SIG_NAME M_H_CPU1_SB_DQ<9>
J 0
(-3390 3610);
DISPLAY 0.659574 (-3390 3610);
PAINT MONO (-3390 3610);
DISPLAY INVISIBLE (-3390 3610);
FORCEPROP 1 LASTPIN (-3400 3600) BN 9
J 0
(-3412 3608);
DISPLAY 0.489362 (-3412 3608);
PAINT GREEN (-3412 3608);
FORCEPROP 2 LAST CDS_LIB mstr_standard
J 0
(-3350 3600);
DISPLAY 0.723404 (-3350 3600);
PAINT MONO (-3350 3600);
DISPLAY INVISIBLE (-3350 3600);
FORCEPROP 1 LAST BODY_TYPE PLUMBING
J 0
(-3350 3650);
DISPLAY 0.872340 (-3350 3650);
PAINT GREEN (-3350 3650);
DISPLAY INVISIBLE (-3350 3650);
FORCEPROP 1 LAST HDL_TAP TRUE
J 0
(-3025 3475);
DISPLAY 0.872340 (-3025 3475);
DISPLAY INVISIBLE (-3025 3475);
FORCEPROP 1 LAST PATH I204
J 0
(-3352 3600);
DISPLAY 0.872340 (-3352 3600);
PAINT GREEN (-3352 3600);
DISPLAY INVISIBLE (-3352 3600);
FORCEADD TAP..1
(-3350 3550);
FORCEPROP 3 LASTPIN (-3400 3550) SIG_NAME M_H_CPU1_SB_DQ<10>
J 0
(-3390 3560);
DISPLAY 0.659574 (-3390 3560);
PAINT MONO (-3390 3560);
DISPLAY INVISIBLE (-3390 3560);
FORCEPROP 1 LASTPIN (-3400 3550) BN 10
J 0
(-3412 3558);
DISPLAY 0.489362 (-3412 3558);
PAINT GREEN (-3412 3558);
FORCEPROP 2 LAST CDS_LIB mstr_standard
J 0
(-3350 3550);
DISPLAY 0.723404 (-3350 3550);
PAINT MONO (-3350 3550);
DISPLAY INVISIBLE (-3350 3550);
FORCEPROP 1 LAST BODY_TYPE PLUMBING
J 0
(-3350 3600);
DISPLAY 0.872340 (-3350 3600);
PAINT GREEN (-3350 3600);
DISPLAY INVISIBLE (-3350 3600);
FORCEPROP 1 LAST HDL_TAP TRUE
J 0
(-3025 3425);
DISPLAY 0.872340 (-3025 3425);
DISPLAY INVISIBLE (-3025 3425);
FORCEPROP 1 LAST PATH I205
J 0
(-3352 3550);
DISPLAY 0.872340 (-3352 3550);
PAINT GREEN (-3352 3550);
DISPLAY INVISIBLE (-3352 3550);
FORCEADD TAP..1
(-3350 3500);
FORCEPROP 3 LASTPIN (-3400 3500) SIG_NAME M_H_CPU1_SB_DQ<11>
J 0
(-3390 3510);
DISPLAY 0.659574 (-3390 3510);
PAINT MONO (-3390 3510);
DISPLAY INVISIBLE (-3390 3510);
FORCEPROP 1 LASTPIN (-3400 3500) BN 11
J 0
(-3412 3508);
DISPLAY 0.489362 (-3412 3508);
PAINT GREEN (-3412 3508);
FORCEPROP 2 LAST CDS_LIB mstr_standard
J 0
(-3350 3500);
DISPLAY 0.723404 (-3350 3500);
PAINT MONO (-3350 3500);
DISPLAY INVISIBLE (-3350 3500);
FORCEPROP 1 LAST BODY_TYPE PLUMBING
J 0
(-3350 3550);
DISPLAY 0.872340 (-3350 3550);
PAINT GREEN (-3350 3550);
DISPLAY INVISIBLE (-3350 3550);
FORCEPROP 1 LAST HDL_TAP TRUE
J 0
(-3025 3375);
DISPLAY 0.872340 (-3025 3375);
DISPLAY INVISIBLE (-3025 3375);
FORCEPROP 1 LAST PATH I206
J 0
(-3352 3500);
DISPLAY 0.872340 (-3352 3500);
PAINT GREEN (-3352 3500);
DISPLAY INVISIBLE (-3352 3500);
FORCEADD TAP..1
(-3350 3350);
FORCEPROP 3 LASTPIN (-3400 3350) SIG_NAME M_H_CPU1_SB_DQ<14>
J 0
(-3390 3360);
DISPLAY 0.659574 (-3390 3360);
PAINT MONO (-3390 3360);
DISPLAY INVISIBLE (-3390 3360);
FORCEPROP 1 LASTPIN (-3400 3350) BN 14
J 0
(-3412 3358);
DISPLAY 0.489362 (-3412 3358);
PAINT GREEN (-3412 3358);
FORCEPROP 2 LAST CDS_LIB mstr_standard
J 0
(-3350 3350);
DISPLAY 0.723404 (-3350 3350);
PAINT MONO (-3350 3350);
DISPLAY INVISIBLE (-3350 3350);
FORCEPROP 1 LAST BODY_TYPE PLUMBING
J 0
(-3350 3400);
DISPLAY 0.872340 (-3350 3400);
PAINT GREEN (-3350 3400);
DISPLAY INVISIBLE (-3350 3400);
FORCEPROP 1 LAST HDL_TAP TRUE
J 0
(-3025 3225);
DISPLAY 0.872340 (-3025 3225);
DISPLAY INVISIBLE (-3025 3225);
FORCEPROP 1 LAST PATH I207
J 0
(-3352 3350);
DISPLAY 0.872340 (-3352 3350);
PAINT GREEN (-3352 3350);
DISPLAY INVISIBLE (-3352 3350);
FORCEADD TAP..1
(-3350 3400);
FORCEPROP 3 LASTPIN (-3400 3400) SIG_NAME M_H_CPU1_SB_DQ<13>
J 0
(-3390 3410);
DISPLAY 0.659574 (-3390 3410);
PAINT MONO (-3390 3410);
DISPLAY INVISIBLE (-3390 3410);
FORCEPROP 1 LASTPIN (-3400 3400) BN 13
J 0
(-3412 3408);
DISPLAY 0.489362 (-3412 3408);
PAINT GREEN (-3412 3408);
FORCEPROP 2 LAST CDS_LIB mstr_standard
J 0
(-3350 3400);
DISPLAY 0.723404 (-3350 3400);
PAINT MONO (-3350 3400);
DISPLAY INVISIBLE (-3350 3400);
FORCEPROP 1 LAST BODY_TYPE PLUMBING
J 0
(-3350 3450);
DISPLAY 0.872340 (-3350 3450);
PAINT GREEN (-3350 3450);
DISPLAY INVISIBLE (-3350 3450);
FORCEPROP 1 LAST HDL_TAP TRUE
J 0
(-3025 3275);
DISPLAY 0.872340 (-3025 3275);
DISPLAY INVISIBLE (-3025 3275);
FORCEPROP 1 LAST PATH I208
J 0
(-3352 3400);
DISPLAY 0.872340 (-3352 3400);
PAINT GREEN (-3352 3400);
DISPLAY INVISIBLE (-3352 3400);
FORCEADD TAP..1
(-3350 3450);
FORCEPROP 3 LASTPIN (-3400 3450) SIG_NAME M_H_CPU1_SB_DQ<12>
J 0
(-3390 3460);
DISPLAY 0.659574 (-3390 3460);
PAINT MONO (-3390 3460);
DISPLAY INVISIBLE (-3390 3460);
FORCEPROP 1 LASTPIN (-3400 3450) BN 12
J 0
(-3412 3458);
DISPLAY 0.489362 (-3412 3458);
PAINT GREEN (-3412 3458);
FORCEPROP 2 LAST CDS_LIB mstr_standard
J 0
(-3350 3450);
DISPLAY 0.723404 (-3350 3450);
PAINT MONO (-3350 3450);
DISPLAY INVISIBLE (-3350 3450);
FORCEPROP 1 LAST BODY_TYPE PLUMBING
J 0
(-3350 3500);
DISPLAY 0.872340 (-3350 3500);
PAINT GREEN (-3350 3500);
DISPLAY INVISIBLE (-3350 3500);
FORCEPROP 1 LAST HDL_TAP TRUE
J 0
(-3025 3325);
DISPLAY 0.872340 (-3025 3325);
DISPLAY INVISIBLE (-3025 3325);
FORCEPROP 1 LAST PATH I209
J 0
(-3352 3450);
DISPLAY 0.872340 (-3352 3450);
PAINT GREEN (-3352 3450);
DISPLAY INVISIBLE (-3352 3450);
FORCEADD TAP..1
(-3350 3150);
FORCEPROP 3 LASTPIN (-3400 3150) SIG_NAME M_H_CPU1_SB_DQ<17>
J 0
(-3390 3160);
DISPLAY 0.659574 (-3390 3160);
PAINT MONO (-3390 3160);
DISPLAY INVISIBLE (-3390 3160);
FORCEPROP 1 LASTPIN (-3400 3150) BN 17
J 0
(-3412 3158);
DISPLAY 0.489362 (-3412 3158);
PAINT GREEN (-3412 3158);
FORCEPROP 2 LAST CDS_LIB mstr_standard
J 0
(-3350 3150);
DISPLAY 0.723404 (-3350 3150);
PAINT MONO (-3350 3150);
DISPLAY INVISIBLE (-3350 3150);
FORCEPROP 1 LAST BODY_TYPE PLUMBING
J 0
(-3350 3200);
DISPLAY 0.872340 (-3350 3200);
PAINT GREEN (-3350 3200);
DISPLAY INVISIBLE (-3350 3200);
FORCEPROP 1 LAST HDL_TAP TRUE
J 0
(-3025 3025);
DISPLAY 0.872340 (-3025 3025);
DISPLAY INVISIBLE (-3025 3025);
FORCEPROP 1 LAST PATH I210
J 0
(-3352 3150);
DISPLAY 0.872340 (-3352 3150);
PAINT GREEN (-3352 3150);
DISPLAY INVISIBLE (-3352 3150);
FORCEADD TAP..1
(-3350 3200);
FORCEPROP 3 LASTPIN (-3400 3200) SIG_NAME M_H_CPU1_SB_DQ<16>
J 0
(-3390 3210);
DISPLAY 0.659574 (-3390 3210);
PAINT MONO (-3390 3210);
DISPLAY INVISIBLE (-3390 3210);
FORCEPROP 1 LASTPIN (-3400 3200) BN 16
J 0
(-3412 3208);
DISPLAY 0.489362 (-3412 3208);
PAINT GREEN (-3412 3208);
FORCEPROP 2 LAST CDS_LIB mstr_standard
J 0
(-3350 3200);
DISPLAY 0.723404 (-3350 3200);
PAINT MONO (-3350 3200);
DISPLAY INVISIBLE (-3350 3200);
FORCEPROP 1 LAST BODY_TYPE PLUMBING
J 0
(-3350 3250);
DISPLAY 0.872340 (-3350 3250);
PAINT GREEN (-3350 3250);
DISPLAY INVISIBLE (-3350 3250);
FORCEPROP 1 LAST HDL_TAP TRUE
J 0
(-3025 3075);
DISPLAY 0.872340 (-3025 3075);
DISPLAY INVISIBLE (-3025 3075);
FORCEPROP 1 LAST PATH I211
J 0
(-3352 3200);
DISPLAY 0.872340 (-3352 3200);
PAINT GREEN (-3352 3200);
DISPLAY INVISIBLE (-3352 3200);
FORCEADD TAP..1
(-3350 3300);
FORCEPROP 3 LASTPIN (-3400 3300) SIG_NAME M_H_CPU1_SB_DQ<15>
J 0
(-3390 3310);
DISPLAY 0.659574 (-3390 3310);
PAINT MONO (-3390 3310);
DISPLAY INVISIBLE (-3390 3310);
FORCEPROP 1 LASTPIN (-3400 3300) BN 15
J 0
(-3412 3308);
DISPLAY 0.489362 (-3412 3308);
PAINT GREEN (-3412 3308);
FORCEPROP 2 LAST CDS_LIB mstr_standard
J 0
(-3350 3300);
DISPLAY 0.723404 (-3350 3300);
PAINT MONO (-3350 3300);
DISPLAY INVISIBLE (-3350 3300);
FORCEPROP 1 LAST BODY_TYPE PLUMBING
J 0
(-3350 3350);
DISPLAY 0.872340 (-3350 3350);
PAINT GREEN (-3350 3350);
DISPLAY INVISIBLE (-3350 3350);
FORCEPROP 1 LAST HDL_TAP TRUE
J 0
(-3025 3175);
DISPLAY 0.872340 (-3025 3175);
DISPLAY INVISIBLE (-3025 3175);
FORCEPROP 1 LAST PATH I212
J 0
(-3352 3300);
DISPLAY 0.872340 (-3352 3300);
PAINT GREEN (-3352 3300);
DISPLAY INVISIBLE (-3352 3300);
FORCEADD TAP..1
(-3350 3100);
FORCEPROP 3 LASTPIN (-3400 3100) SIG_NAME M_H_CPU1_SB_DQ<18>
J 0
(-3390 3110);
DISPLAY 0.659574 (-3390 3110);
PAINT MONO (-3390 3110);
DISPLAY INVISIBLE (-3390 3110);
FORCEPROP 1 LASTPIN (-3400 3100) BN 18
J 0
(-3412 3108);
DISPLAY 0.489362 (-3412 3108);
PAINT GREEN (-3412 3108);
FORCEPROP 2 LAST CDS_LIB mstr_standard
J 0
(-3350 3100);
DISPLAY 0.723404 (-3350 3100);
PAINT MONO (-3350 3100);
DISPLAY INVISIBLE (-3350 3100);
FORCEPROP 1 LAST BODY_TYPE PLUMBING
J 0
(-3350 3150);
DISPLAY 0.872340 (-3350 3150);
PAINT GREEN (-3350 3150);
DISPLAY INVISIBLE (-3350 3150);
FORCEPROP 1 LAST HDL_TAP TRUE
J 0
(-3025 2975);
DISPLAY 0.872340 (-3025 2975);
DISPLAY INVISIBLE (-3025 2975);
FORCEPROP 1 LAST PATH I213
J 0
(-3352 3100);
DISPLAY 0.872340 (-3352 3100);
PAINT GREEN (-3352 3100);
DISPLAY INVISIBLE (-3352 3100);
FORCEADD TAP..1
(-3350 2950);
FORCEPROP 3 LASTPIN (-3400 2950) SIG_NAME M_H_CPU1_SB_DQ<21>
J 0
(-3390 2960);
DISPLAY 0.659574 (-3390 2960);
PAINT MONO (-3390 2960);
DISPLAY INVISIBLE (-3390 2960);
FORCEPROP 1 LASTPIN (-3400 2950) BN 21
J 0
(-3412 2958);
DISPLAY 0.489362 (-3412 2958);
PAINT GREEN (-3412 2958);
FORCEPROP 2 LAST CDS_LIB mstr_standard
J 0
(-3350 2950);
DISPLAY 0.723404 (-3350 2950);
PAINT MONO (-3350 2950);
DISPLAY INVISIBLE (-3350 2950);
FORCEPROP 1 LAST BODY_TYPE PLUMBING
J 0
(-3350 3000);
DISPLAY 0.872340 (-3350 3000);
PAINT GREEN (-3350 3000);
DISPLAY INVISIBLE (-3350 3000);
FORCEPROP 1 LAST HDL_TAP TRUE
J 0
(-3025 2825);
DISPLAY 0.872340 (-3025 2825);
DISPLAY INVISIBLE (-3025 2825);
FORCEPROP 1 LAST PATH I214
J 0
(-3352 2950);
DISPLAY 0.872340 (-3352 2950);
PAINT GREEN (-3352 2950);
DISPLAY INVISIBLE (-3352 2950);
FORCEADD TAP..1
(-3350 3050);
FORCEPROP 3 LASTPIN (-3400 3050) SIG_NAME M_H_CPU1_SB_DQ<19>
J 0
(-3390 3060);
DISPLAY 0.659574 (-3390 3060);
PAINT MONO (-3390 3060);
DISPLAY INVISIBLE (-3390 3060);
FORCEPROP 1 LASTPIN (-3400 3050) BN 19
J 0
(-3412 3058);
DISPLAY 0.489362 (-3412 3058);
PAINT GREEN (-3412 3058);
FORCEPROP 2 LAST CDS_LIB mstr_standard
J 0
(-3350 3050);
DISPLAY 0.723404 (-3350 3050);
PAINT MONO (-3350 3050);
DISPLAY INVISIBLE (-3350 3050);
FORCEPROP 1 LAST BODY_TYPE PLUMBING
J 0
(-3350 3100);
DISPLAY 0.872340 (-3350 3100);
PAINT GREEN (-3350 3100);
DISPLAY INVISIBLE (-3350 3100);
FORCEPROP 1 LAST HDL_TAP TRUE
J 0
(-3025 2925);
DISPLAY 0.872340 (-3025 2925);
DISPLAY INVISIBLE (-3025 2925);
FORCEPROP 1 LAST PATH I215
J 0
(-3352 3050);
DISPLAY 0.872340 (-3352 3050);
PAINT GREEN (-3352 3050);
DISPLAY INVISIBLE (-3352 3050);
FORCEADD TAP..1
(-3350 3000);
FORCEPROP 3 LASTPIN (-3400 3000) SIG_NAME M_H_CPU1_SB_DQ<20>
J 0
(-3390 3010);
DISPLAY 0.659574 (-3390 3010);
PAINT MONO (-3390 3010);
DISPLAY INVISIBLE (-3390 3010);
FORCEPROP 1 LASTPIN (-3400 3000) BN 20
J 0
(-3412 3008);
DISPLAY 0.489362 (-3412 3008);
PAINT GREEN (-3412 3008);
FORCEPROP 2 LAST CDS_LIB mstr_standard
J 0
(-3350 3000);
DISPLAY 0.723404 (-3350 3000);
PAINT MONO (-3350 3000);
DISPLAY INVISIBLE (-3350 3000);
FORCEPROP 1 LAST BODY_TYPE PLUMBING
J 0
(-3350 3050);
DISPLAY 0.872340 (-3350 3050);
PAINT GREEN (-3350 3050);
DISPLAY INVISIBLE (-3350 3050);
FORCEPROP 1 LAST HDL_TAP TRUE
J 0
(-3025 2875);
DISPLAY 0.872340 (-3025 2875);
DISPLAY INVISIBLE (-3025 2875);
FORCEPROP 1 LAST PATH I216
J 0
(-3352 3000);
DISPLAY 0.872340 (-3352 3000);
PAINT GREEN (-3352 3000);
DISPLAY INVISIBLE (-3352 3000);
FORCEADD TAP..1
(-3350 2850);
FORCEPROP 3 LASTPIN (-3400 2850) SIG_NAME M_H_CPU1_SB_DQ<23>
J 0
(-3390 2860);
DISPLAY 0.659574 (-3390 2860);
PAINT MONO (-3390 2860);
DISPLAY INVISIBLE (-3390 2860);
FORCEPROP 1 LASTPIN (-3400 2850) BN 23
J 0
(-3412 2858);
DISPLAY 0.489362 (-3412 2858);
PAINT GREEN (-3412 2858);
FORCEPROP 2 LAST CDS_LIB mstr_standard
J 0
(-3350 2850);
DISPLAY 0.723404 (-3350 2850);
PAINT MONO (-3350 2850);
DISPLAY INVISIBLE (-3350 2850);
FORCEPROP 1 LAST BODY_TYPE PLUMBING
J 0
(-3350 2900);
DISPLAY 0.872340 (-3350 2900);
PAINT GREEN (-3350 2900);
DISPLAY INVISIBLE (-3350 2900);
FORCEPROP 1 LAST HDL_TAP TRUE
J 0
(-3025 2725);
DISPLAY 0.872340 (-3025 2725);
DISPLAY INVISIBLE (-3025 2725);
FORCEPROP 1 LAST PATH I217
J 0
(-3352 2850);
DISPLAY 0.872340 (-3352 2850);
PAINT GREEN (-3352 2850);
DISPLAY INVISIBLE (-3352 2850);
FORCEADD TAP..1
(-3350 2900);
FORCEPROP 3 LASTPIN (-3400 2900) SIG_NAME M_H_CPU1_SB_DQ<22>
J 0
(-3390 2910);
DISPLAY 0.659574 (-3390 2910);
PAINT MONO (-3390 2910);
DISPLAY INVISIBLE (-3390 2910);
FORCEPROP 1 LASTPIN (-3400 2900) BN 22
J 0
(-3412 2908);
DISPLAY 0.489362 (-3412 2908);
PAINT GREEN (-3412 2908);
FORCEPROP 2 LAST CDS_LIB mstr_standard
J 0
(-3350 2900);
DISPLAY 0.723404 (-3350 2900);
PAINT MONO (-3350 2900);
DISPLAY INVISIBLE (-3350 2900);
FORCEPROP 1 LAST BODY_TYPE PLUMBING
J 0
(-3350 2950);
DISPLAY 0.872340 (-3350 2950);
PAINT GREEN (-3350 2950);
DISPLAY INVISIBLE (-3350 2950);
FORCEPROP 1 LAST HDL_TAP TRUE
J 0
(-3025 2775);
DISPLAY 0.872340 (-3025 2775);
DISPLAY INVISIBLE (-3025 2775);
FORCEPROP 1 LAST PATH I218
J 0
(-3352 2900);
DISPLAY 0.872340 (-3352 2900);
PAINT GREEN (-3352 2900);
DISPLAY INVISIBLE (-3352 2900);
FORCEADD TAP..1
(-3350 2650);
FORCEPROP 3 LASTPIN (-3400 2650) SIG_NAME M_H_CPU1_SB_DQ<26>
J 0
(-3390 2660);
DISPLAY 0.659574 (-3390 2660);
PAINT MONO (-3390 2660);
DISPLAY INVISIBLE (-3390 2660);
FORCEPROP 1 LASTPIN (-3400 2650) BN 26
J 0
(-3412 2658);
DISPLAY 0.489362 (-3412 2658);
PAINT GREEN (-3412 2658);
FORCEPROP 2 LAST CDS_LIB mstr_standard
J 0
(-3350 2650);
DISPLAY 0.723404 (-3350 2650);
PAINT MONO (-3350 2650);
DISPLAY INVISIBLE (-3350 2650);
FORCEPROP 1 LAST BODY_TYPE PLUMBING
J 0
(-3350 2700);
DISPLAY 0.872340 (-3350 2700);
PAINT GREEN (-3350 2700);
DISPLAY INVISIBLE (-3350 2700);
FORCEPROP 1 LAST HDL_TAP TRUE
J 0
(-3025 2525);
DISPLAY 0.872340 (-3025 2525);
DISPLAY INVISIBLE (-3025 2525);
FORCEPROP 1 LAST PATH I219
J 0
(-3352 2650);
DISPLAY 0.872340 (-3352 2650);
PAINT GREEN (-3352 2650);
DISPLAY INVISIBLE (-3352 2650);
FORCEADD TAP..1
(-3350 2700);
FORCEPROP 3 LASTPIN (-3400 2700) SIG_NAME M_H_CPU1_SB_DQ<25>
J 0
(-3390 2710);
DISPLAY 0.659574 (-3390 2710);
PAINT MONO (-3390 2710);
DISPLAY INVISIBLE (-3390 2710);
FORCEPROP 1 LASTPIN (-3400 2700) BN 25
J 0
(-3412 2708);
DISPLAY 0.489362 (-3412 2708);
PAINT GREEN (-3412 2708);
FORCEPROP 2 LAST CDS_LIB mstr_standard
J 0
(-3350 2700);
DISPLAY 0.723404 (-3350 2700);
PAINT MONO (-3350 2700);
DISPLAY INVISIBLE (-3350 2700);
FORCEPROP 1 LAST BODY_TYPE PLUMBING
J 0
(-3350 2750);
DISPLAY 0.872340 (-3350 2750);
PAINT GREEN (-3350 2750);
DISPLAY INVISIBLE (-3350 2750);
FORCEPROP 1 LAST HDL_TAP TRUE
J 0
(-3025 2575);
DISPLAY 0.872340 (-3025 2575);
DISPLAY INVISIBLE (-3025 2575);
FORCEPROP 1 LAST PATH I220
J 0
(-3352 2700);
DISPLAY 0.872340 (-3352 2700);
PAINT GREEN (-3352 2700);
DISPLAY INVISIBLE (-3352 2700);
FORCEADD TAP..1
(-3350 2750);
FORCEPROP 3 LASTPIN (-3400 2750) SIG_NAME M_H_CPU1_SB_DQ<24>
J 0
(-3390 2760);
DISPLAY 0.659574 (-3390 2760);
PAINT MONO (-3390 2760);
DISPLAY INVISIBLE (-3390 2760);
FORCEPROP 1 LASTPIN (-3400 2750) BN 24
J 0
(-3412 2758);
DISPLAY 0.489362 (-3412 2758);
PAINT GREEN (-3412 2758);
FORCEPROP 2 LAST CDS_LIB mstr_standard
J 0
(-3350 2750);
DISPLAY 0.723404 (-3350 2750);
PAINT MONO (-3350 2750);
DISPLAY INVISIBLE (-3350 2750);
FORCEPROP 1 LAST BODY_TYPE PLUMBING
J 0
(-3350 2800);
DISPLAY 0.872340 (-3350 2800);
PAINT GREEN (-3350 2800);
DISPLAY INVISIBLE (-3350 2800);
FORCEPROP 1 LAST HDL_TAP TRUE
J 0
(-3025 2625);
DISPLAY 0.872340 (-3025 2625);
DISPLAY INVISIBLE (-3025 2625);
FORCEPROP 1 LAST PATH I221
J 0
(-3352 2750);
DISPLAY 0.872340 (-3352 2750);
PAINT GREEN (-3352 2750);
DISPLAY INVISIBLE (-3352 2750);
FORCEADD TAP..1
(-3350 2600);
FORCEPROP 3 LASTPIN (-3400 2600) SIG_NAME M_H_CPU1_SB_DQ<27>
J 0
(-3390 2610);
DISPLAY 0.659574 (-3390 2610);
PAINT MONO (-3390 2610);
DISPLAY INVISIBLE (-3390 2610);
FORCEPROP 1 LASTPIN (-3400 2600) BN 27
J 0
(-3412 2608);
DISPLAY 0.489362 (-3412 2608);
PAINT GREEN (-3412 2608);
FORCEPROP 2 LAST CDS_LIB mstr_standard
J 0
(-3350 2600);
DISPLAY 0.723404 (-3350 2600);
PAINT MONO (-3350 2600);
DISPLAY INVISIBLE (-3350 2600);
FORCEPROP 1 LAST BODY_TYPE PLUMBING
J 0
(-3350 2650);
DISPLAY 0.872340 (-3350 2650);
PAINT GREEN (-3350 2650);
DISPLAY INVISIBLE (-3350 2650);
FORCEPROP 1 LAST HDL_TAP TRUE
J 0
(-3025 2475);
DISPLAY 0.872340 (-3025 2475);
DISPLAY INVISIBLE (-3025 2475);
FORCEPROP 1 LAST PATH I222
J 0
(-3352 2600);
DISPLAY 0.872340 (-3352 2600);
PAINT GREEN (-3352 2600);
DISPLAY INVISIBLE (-3352 2600);
FORCEADD TAP..1
(-3350 2400);
FORCEPROP 3 LASTPIN (-3400 2400) SIG_NAME M_H_CPU1_SB_DQ<31>
J 0
(-3390 2410);
DISPLAY 0.659574 (-3390 2410);
PAINT MONO (-3390 2410);
DISPLAY INVISIBLE (-3390 2410);
FORCEPROP 1 LASTPIN (-3400 2400) BN 31
J 0
(-3412 2408);
DISPLAY 0.489362 (-3412 2408);
PAINT GREEN (-3412 2408);
FORCEPROP 2 LAST CDS_LIB mstr_standard
J 0
(-3350 2400);
DISPLAY 0.723404 (-3350 2400);
PAINT MONO (-3350 2400);
DISPLAY INVISIBLE (-3350 2400);
FORCEPROP 1 LAST BODY_TYPE PLUMBING
J 0
(-3350 2450);
DISPLAY 0.872340 (-3350 2450);
PAINT GREEN (-3350 2450);
DISPLAY INVISIBLE (-3350 2450);
FORCEPROP 1 LAST HDL_TAP TRUE
J 0
(-3025 2275);
DISPLAY 0.872340 (-3025 2275);
DISPLAY INVISIBLE (-3025 2275);
FORCEPROP 1 LAST PATH I223
J 0
(-3352 2400);
DISPLAY 0.872340 (-3352 2400);
PAINT GREEN (-3352 2400);
DISPLAY INVISIBLE (-3352 2400);
FORCEADD TAP..1
(-3350 2550);
FORCEPROP 3 LASTPIN (-3400 2550) SIG_NAME M_H_CPU1_SB_DQ<28>
J 0
(-3390 2560);
DISPLAY 0.659574 (-3390 2560);
PAINT MONO (-3390 2560);
DISPLAY INVISIBLE (-3390 2560);
FORCEPROP 1 LASTPIN (-3400 2550) BN 28
J 0
(-3412 2558);
DISPLAY 0.489362 (-3412 2558);
PAINT GREEN (-3412 2558);
FORCEPROP 2 LAST CDS_LIB mstr_standard
J 0
(-3350 2550);
DISPLAY 0.723404 (-3350 2550);
PAINT MONO (-3350 2550);
DISPLAY INVISIBLE (-3350 2550);
FORCEPROP 1 LAST BODY_TYPE PLUMBING
J 0
(-3350 2600);
DISPLAY 0.872340 (-3350 2600);
PAINT GREEN (-3350 2600);
DISPLAY INVISIBLE (-3350 2600);
FORCEPROP 1 LAST HDL_TAP TRUE
J 0
(-3025 2425);
DISPLAY 0.872340 (-3025 2425);
DISPLAY INVISIBLE (-3025 2425);
FORCEPROP 1 LAST PATH I224
J 0
(-3352 2550);
DISPLAY 0.872340 (-3352 2550);
PAINT GREEN (-3352 2550);
DISPLAY INVISIBLE (-3352 2550);
FORCEADD TAP..1
(-3350 2500);
FORCEPROP 3 LASTPIN (-3400 2500) SIG_NAME M_H_CPU1_SB_DQ<29>
J 0
(-3390 2510);
DISPLAY 0.659574 (-3390 2510);
PAINT MONO (-3390 2510);
DISPLAY INVISIBLE (-3390 2510);
FORCEPROP 1 LASTPIN (-3400 2500) BN 29
J 0
(-3412 2508);
DISPLAY 0.489362 (-3412 2508);
PAINT GREEN (-3412 2508);
FORCEPROP 2 LAST CDS_LIB mstr_standard
J 0
(-3350 2500);
DISPLAY 0.723404 (-3350 2500);
PAINT MONO (-3350 2500);
DISPLAY INVISIBLE (-3350 2500);
FORCEPROP 1 LAST BODY_TYPE PLUMBING
J 0
(-3350 2550);
DISPLAY 0.872340 (-3350 2550);
PAINT GREEN (-3350 2550);
DISPLAY INVISIBLE (-3350 2550);
FORCEPROP 1 LAST HDL_TAP TRUE
J 0
(-3025 2375);
DISPLAY 0.872340 (-3025 2375);
DISPLAY INVISIBLE (-3025 2375);
FORCEPROP 1 LAST PATH I225
J 0
(-3352 2500);
DISPLAY 0.872340 (-3352 2500);
PAINT GREEN (-3352 2500);
DISPLAY INVISIBLE (-3352 2500);
FORCEADD TAP..1
(-3350 2450);
FORCEPROP 3 LASTPIN (-3400 2450) SIG_NAME M_H_CPU1_SB_DQ<30>
J 0
(-3390 2460);
DISPLAY 0.659574 (-3390 2460);
PAINT MONO (-3390 2460);
DISPLAY INVISIBLE (-3390 2460);
FORCEPROP 1 LASTPIN (-3400 2450) BN 30
J 0
(-3412 2458);
DISPLAY 0.489362 (-3412 2458);
PAINT GREEN (-3412 2458);
FORCEPROP 2 LAST CDS_LIB mstr_standard
J 0
(-3350 2450);
DISPLAY 0.723404 (-3350 2450);
PAINT MONO (-3350 2450);
DISPLAY INVISIBLE (-3350 2450);
FORCEPROP 1 LAST BODY_TYPE PLUMBING
J 0
(-3350 2500);
DISPLAY 0.872340 (-3350 2500);
PAINT GREEN (-3350 2500);
DISPLAY INVISIBLE (-3350 2500);
FORCEPROP 1 LAST HDL_TAP TRUE
J 0
(-3025 2325);
DISPLAY 0.872340 (-3025 2325);
DISPLAY INVISIBLE (-3025 2325);
FORCEPROP 1 LAST PATH I226
J 0
(-3352 2450);
DISPLAY 0.872340 (-3352 2450);
PAINT GREEN (-3352 2450);
DISPLAY INVISIBLE (-3352 2450);
FORCEADD TAP..1
(-3350 2250);
FORCEPROP 3 LASTPIN (-3400 2250) SIG_NAME M_H_CPU1_SA_CB<1>
J 0
(-3390 2260);
DISPLAY 0.659574 (-3390 2260);
PAINT MONO (-3390 2260);
DISPLAY INVISIBLE (-3390 2260);
FORCEPROP 1 LASTPIN (-3400 2250) BN 1
J 0
(-3412 2258);
DISPLAY 0.489362 (-3412 2258);
PAINT GREEN (-3412 2258);
FORCEPROP 2 LAST CDS_LIB mstr_standard
J 2
(-3350 2250);
DISPLAY 0.723404 (-3350 2250);
PAINT MONO (-3350 2250);
DISPLAY INVISIBLE (-3350 2250);
FORCEPROP 1 LAST BODY_TYPE PLUMBING
J 0
(-3350 2300);
DISPLAY 0.872340 (-3350 2300);
PAINT GREEN (-3350 2300);
DISPLAY INVISIBLE (-3350 2300);
FORCEPROP 1 LAST HDL_TAP TRUE
J 0
(-3025 2125);
DISPLAY 0.872340 (-3025 2125);
DISPLAY INVISIBLE (-3025 2125);
FORCEPROP 1 LAST PATH I227
J 0
(-3352 2250);
DISPLAY 0.872340 (-3352 2250);
PAINT GREEN (-3352 2250);
DISPLAY INVISIBLE (-3352 2250);
FORCEADD TAP..1
(-3350 2300);
FORCEPROP 3 LASTPIN (-3400 2300) SIG_NAME M_H_CPU1_SA_CB<0>
J 0
(-3390 2310);
DISPLAY 0.659574 (-3390 2310);
PAINT MONO (-3390 2310);
DISPLAY INVISIBLE (-3390 2310);
FORCEPROP 1 LASTPIN (-3400 2300) BN 0
J 0
(-3412 2308);
DISPLAY 0.489362 (-3412 2308);
PAINT GREEN (-3412 2308);
FORCEPROP 2 LAST CDS_LIB mstr_standard
J 2
(-3350 2300);
DISPLAY 0.723404 (-3350 2300);
PAINT MONO (-3350 2300);
DISPLAY INVISIBLE (-3350 2300);
FORCEPROP 1 LAST BODY_TYPE PLUMBING
J 0
(-3350 2350);
DISPLAY 0.872340 (-3350 2350);
PAINT GREEN (-3350 2350);
DISPLAY INVISIBLE (-3350 2350);
FORCEPROP 1 LAST HDL_TAP TRUE
J 0
(-3025 2175);
DISPLAY 0.872340 (-3025 2175);
DISPLAY INVISIBLE (-3025 2175);
FORCEPROP 1 LAST PATH I228
J 0
(-3352 2300);
DISPLAY 0.872340 (-3352 2300);
PAINT GREEN (-3352 2300);
DISPLAY INVISIBLE (-3352 2300);
FORCEADD TAP..1
(-3350 2200);
FORCEPROP 3 LASTPIN (-3400 2200) SIG_NAME M_H_CPU1_SA_CB<2>
J 0
(-3390 2210);
DISPLAY 0.659574 (-3390 2210);
PAINT MONO (-3390 2210);
DISPLAY INVISIBLE (-3390 2210);
FORCEPROP 1 LASTPIN (-3400 2200) BN 2
J 0
(-3412 2208);
DISPLAY 0.489362 (-3412 2208);
PAINT GREEN (-3412 2208);
FORCEPROP 2 LAST CDS_LIB mstr_standard
J 2
(-3350 2200);
DISPLAY 0.723404 (-3350 2200);
PAINT MONO (-3350 2200);
DISPLAY INVISIBLE (-3350 2200);
FORCEPROP 1 LAST BODY_TYPE PLUMBING
J 0
(-3350 2250);
DISPLAY 0.872340 (-3350 2250);
PAINT GREEN (-3350 2250);
DISPLAY INVISIBLE (-3350 2250);
FORCEPROP 1 LAST HDL_TAP TRUE
J 0
(-3025 2075);
DISPLAY 0.872340 (-3025 2075);
DISPLAY INVISIBLE (-3025 2075);
FORCEPROP 1 LAST PATH I229
J 0
(-3352 2200);
DISPLAY 0.872340 (-3352 2200);
PAINT GREEN (-3352 2200);
DISPLAY INVISIBLE (-3352 2200);
FORCEADD TAP..1
(-3350 2150);
FORCEPROP 3 LASTPIN (-3400 2150) SIG_NAME M_H_CPU1_SA_CB<3>
J 0
(-3390 2160);
DISPLAY 0.659574 (-3390 2160);
PAINT MONO (-3390 2160);
DISPLAY INVISIBLE (-3390 2160);
FORCEPROP 1 LASTPIN (-3400 2150) BN 3
J 0
(-3412 2158);
DISPLAY 0.489362 (-3412 2158);
PAINT GREEN (-3412 2158);
FORCEPROP 2 LAST CDS_LIB mstr_standard
J 2
(-3350 2150);
DISPLAY 0.723404 (-3350 2150);
PAINT MONO (-3350 2150);
DISPLAY INVISIBLE (-3350 2150);
FORCEPROP 1 LAST BODY_TYPE PLUMBING
J 0
(-3350 2200);
DISPLAY 0.872340 (-3350 2200);
PAINT GREEN (-3350 2200);
DISPLAY INVISIBLE (-3350 2200);
FORCEPROP 1 LAST HDL_TAP TRUE
J 0
(-3025 2025);
DISPLAY 0.872340 (-3025 2025);
DISPLAY INVISIBLE (-3025 2025);
FORCEPROP 1 LAST PATH I230
J 0
(-3352 2150);
DISPLAY 0.872340 (-3352 2150);
PAINT GREEN (-3352 2150);
DISPLAY INVISIBLE (-3352 2150);
FORCEADD TAP..1
(-3350 2050);
FORCEPROP 3 LASTPIN (-3400 2050) SIG_NAME M_H_CPU1_SA_CB<5>
J 0
(-3390 2060);
DISPLAY 0.659574 (-3390 2060);
PAINT MONO (-3390 2060);
DISPLAY INVISIBLE (-3390 2060);
FORCEPROP 1 LASTPIN (-3400 2050) BN 5
J 0
(-3412 2058);
DISPLAY 0.489362 (-3412 2058);
PAINT GREEN (-3412 2058);
FORCEPROP 2 LAST CDS_LIB mstr_standard
J 2
(-3350 2050);
DISPLAY 0.723404 (-3350 2050);
PAINT MONO (-3350 2050);
DISPLAY INVISIBLE (-3350 2050);
FORCEPROP 1 LAST BODY_TYPE PLUMBING
J 0
(-3350 2100);
DISPLAY 0.872340 (-3350 2100);
PAINT GREEN (-3350 2100);
DISPLAY INVISIBLE (-3350 2100);
FORCEPROP 1 LAST HDL_TAP TRUE
J 0
(-3025 1925);
DISPLAY 0.872340 (-3025 1925);
DISPLAY INVISIBLE (-3025 1925);
FORCEPROP 1 LAST PATH I231
J 0
(-3352 2050);
DISPLAY 0.872340 (-3352 2050);
PAINT GREEN (-3352 2050);
DISPLAY INVISIBLE (-3352 2050);
FORCEADD TAP..1
(-3350 2100);
FORCEPROP 3 LASTPIN (-3400 2100) SIG_NAME M_H_CPU1_SA_CB<4>
J 0
(-3390 2110);
DISPLAY 0.659574 (-3390 2110);
PAINT MONO (-3390 2110);
DISPLAY INVISIBLE (-3390 2110);
FORCEPROP 1 LASTPIN (-3400 2100) BN 4
J 0
(-3412 2108);
DISPLAY 0.489362 (-3412 2108);
PAINT GREEN (-3412 2108);
FORCEPROP 2 LAST CDS_LIB mstr_standard
J 2
(-3350 2100);
DISPLAY 0.723404 (-3350 2100);
PAINT MONO (-3350 2100);
DISPLAY INVISIBLE (-3350 2100);
FORCEPROP 1 LAST BODY_TYPE PLUMBING
J 0
(-3350 2150);
DISPLAY 0.872340 (-3350 2150);
PAINT GREEN (-3350 2150);
DISPLAY INVISIBLE (-3350 2150);
FORCEPROP 1 LAST HDL_TAP TRUE
J 0
(-3025 1975);
DISPLAY 0.872340 (-3025 1975);
DISPLAY INVISIBLE (-3025 1975);
FORCEPROP 1 LAST PATH I232
J 0
(-3352 2100);
DISPLAY 0.872340 (-3352 2100);
PAINT GREEN (-3352 2100);
DISPLAY INVISIBLE (-3352 2100);
FORCEADD OFFPAGE..6
R 2
(-2750 1900);
FORCEPROP 2 LAST $XR0 105 
J 0
(-2536 1900);
DISPLAY 0.638298 (-2536 1900);
PAINT MONO (-2536 1900);
FORCEPROP 2 LAST CDS_LIB mstr_standard
J 2
(-2750 1900);
DISPLAY 0.723404 (-2750 1900);
PAINT MONO (-2750 1900);
DISPLAY INVISIBLE (-2750 1900);
FORCEPROP 1 LAST OFFPAGE TRUE
J 2
(-3075 1775);
DISPLAY 0.872340 (-3075 1775);
PAINT GREEN (-3075 1775);
DISPLAY INVISIBLE (-3075 1775);
FORCEPROP 1 LAST COMMENT_BODY TRUE
J 2
(-2850 1825);
DISPLAY 0.872340 (-2850 1825);
PAINT GREEN (-2850 1825);
DISPLAY INVISIBLE (-2850 1825);
FORCEPROP 2 LAST PATH I233
J 0
(-2525 1950);
DISPLAY 1.021277 (-2525 1950);
DISPLAY INVISIBLE (-2525 1950);
FORCEADD TAP..1
(-3350 1950);
FORCEPROP 3 LASTPIN (-3400 1950) SIG_NAME M_H_CPU1_SA_CB<7>
J 0
(-3390 1960);
DISPLAY 0.659574 (-3390 1960);
PAINT MONO (-3390 1960);
DISPLAY INVISIBLE (-3390 1960);
FORCEPROP 1 LASTPIN (-3400 1950) BN 7
J 0
(-3412 1958);
DISPLAY 0.489362 (-3412 1958);
PAINT GREEN (-3412 1958);
FORCEPROP 2 LAST CDS_LIB mstr_standard
J 2
(-3350 1950);
DISPLAY 0.723404 (-3350 1950);
PAINT MONO (-3350 1950);
DISPLAY INVISIBLE (-3350 1950);
FORCEPROP 1 LAST BODY_TYPE PLUMBING
J 0
(-3350 2000);
DISPLAY 0.872340 (-3350 2000);
PAINT GREEN (-3350 2000);
DISPLAY INVISIBLE (-3350 2000);
FORCEPROP 1 LAST HDL_TAP TRUE
J 0
(-3025 1825);
DISPLAY 0.872340 (-3025 1825);
DISPLAY INVISIBLE (-3025 1825);
FORCEPROP 1 LAST PATH I234
J 0
(-3352 1950);
DISPLAY 0.872340 (-3352 1950);
PAINT GREEN (-3352 1950);
DISPLAY INVISIBLE (-3352 1950);
FORCEADD TAP..1
(-3350 1850);
FORCEPROP 3 LASTPIN (-3400 1850) SIG_NAME M_H_CPU1_SB_CB<0>
J 0
(-3390 1860);
DISPLAY 0.659574 (-3390 1860);
PAINT MONO (-3390 1860);
DISPLAY INVISIBLE (-3390 1860);
FORCEPROP 1 LASTPIN (-3400 1850) BN 0
J 0
(-3412 1858);
DISPLAY 0.489362 (-3412 1858);
PAINT GREEN (-3412 1858);
FORCEPROP 2 LAST CDS_LIB mstr_standard
J 2
(-3350 1850);
DISPLAY 0.723404 (-3350 1850);
PAINT MONO (-3350 1850);
DISPLAY INVISIBLE (-3350 1850);
FORCEPROP 1 LAST BODY_TYPE PLUMBING
J 0
(-3350 1900);
DISPLAY 0.872340 (-3350 1900);
PAINT GREEN (-3350 1900);
DISPLAY INVISIBLE (-3350 1900);
FORCEPROP 1 LAST HDL_TAP TRUE
J 0
(-3025 1725);
DISPLAY 0.872340 (-3025 1725);
DISPLAY INVISIBLE (-3025 1725);
FORCEPROP 1 LAST PATH I235
J 0
(-3352 1850);
DISPLAY 0.872340 (-3352 1850);
PAINT GREEN (-3352 1850);
DISPLAY INVISIBLE (-3352 1850);
FORCEADD TAP..1
(-3350 2000);
FORCEPROP 3 LASTPIN (-3400 2000) SIG_NAME M_H_CPU1_SA_CB<6>
J 0
(-3390 2010);
DISPLAY 0.659574 (-3390 2010);
PAINT MONO (-3390 2010);
DISPLAY INVISIBLE (-3390 2010);
FORCEPROP 1 LASTPIN (-3400 2000) BN 6
J 0
(-3412 2008);
DISPLAY 0.489362 (-3412 2008);
PAINT GREEN (-3412 2008);
FORCEPROP 2 LAST CDS_LIB mstr_standard
J 2
(-3350 2000);
DISPLAY 0.723404 (-3350 2000);
PAINT MONO (-3350 2000);
DISPLAY INVISIBLE (-3350 2000);
FORCEPROP 1 LAST BODY_TYPE PLUMBING
J 0
(-3350 2050);
DISPLAY 0.872340 (-3350 2050);
PAINT GREEN (-3350 2050);
DISPLAY INVISIBLE (-3350 2050);
FORCEPROP 1 LAST HDL_TAP TRUE
J 0
(-3025 1875);
DISPLAY 0.872340 (-3025 1875);
DISPLAY INVISIBLE (-3025 1875);
FORCEPROP 1 LAST PATH I236
J 0
(-3352 2000);
DISPLAY 0.872340 (-3352 2000);
PAINT GREEN (-3352 2000);
DISPLAY INVISIBLE (-3352 2000);
FORCEADD TAP..1
(-3350 1800);
FORCEPROP 3 LASTPIN (-3400 1800) SIG_NAME M_H_CPU1_SB_CB<1>
J 0
(-3390 1810);
DISPLAY 0.659574 (-3390 1810);
PAINT MONO (-3390 1810);
DISPLAY INVISIBLE (-3390 1810);
FORCEPROP 1 LASTPIN (-3400 1800) BN 1
J 0
(-3412 1808);
DISPLAY 0.489362 (-3412 1808);
PAINT GREEN (-3412 1808);
FORCEPROP 2 LAST CDS_LIB mstr_standard
J 2
(-3350 1800);
DISPLAY 0.723404 (-3350 1800);
PAINT MONO (-3350 1800);
DISPLAY INVISIBLE (-3350 1800);
FORCEPROP 1 LAST BODY_TYPE PLUMBING
J 0
(-3350 1850);
DISPLAY 0.872340 (-3350 1850);
PAINT GREEN (-3350 1850);
DISPLAY INVISIBLE (-3350 1850);
FORCEPROP 1 LAST HDL_TAP TRUE
J 0
(-3025 1675);
DISPLAY 0.872340 (-3025 1675);
DISPLAY INVISIBLE (-3025 1675);
FORCEPROP 1 LAST PATH I237
J 0
(-3352 1800);
DISPLAY 0.872340 (-3352 1800);
PAINT GREEN (-3352 1800);
DISPLAY INVISIBLE (-3352 1800);
FORCEADD TAP..1
(-3350 1750);
FORCEPROP 3 LASTPIN (-3400 1750) SIG_NAME M_H_CPU1_SB_CB<2>
J 0
(-3390 1760);
DISPLAY 0.659574 (-3390 1760);
PAINT MONO (-3390 1760);
DISPLAY INVISIBLE (-3390 1760);
FORCEPROP 1 LASTPIN (-3400 1750) BN 2
J 0
(-3412 1758);
DISPLAY 0.489362 (-3412 1758);
PAINT GREEN (-3412 1758);
FORCEPROP 2 LAST CDS_LIB mstr_standard
J 2
(-3350 1750);
DISPLAY 0.723404 (-3350 1750);
PAINT MONO (-3350 1750);
DISPLAY INVISIBLE (-3350 1750);
FORCEPROP 1 LAST BODY_TYPE PLUMBING
J 0
(-3350 1800);
DISPLAY 0.872340 (-3350 1800);
PAINT GREEN (-3350 1800);
DISPLAY INVISIBLE (-3350 1800);
FORCEPROP 1 LAST HDL_TAP TRUE
J 0
(-3025 1625);
DISPLAY 0.872340 (-3025 1625);
DISPLAY INVISIBLE (-3025 1625);
FORCEPROP 1 LAST PATH I238
J 0
(-3352 1750);
DISPLAY 0.872340 (-3352 1750);
PAINT GREEN (-3352 1750);
DISPLAY INVISIBLE (-3352 1750);
FORCEADD TAP..1
(-3350 1700);
FORCEPROP 3 LASTPIN (-3400 1700) SIG_NAME M_H_CPU1_SB_CB<3>
J 0
(-3390 1710);
DISPLAY 0.659574 (-3390 1710);
PAINT MONO (-3390 1710);
DISPLAY INVISIBLE (-3390 1710);
FORCEPROP 1 LASTPIN (-3400 1700) BN 3
J 0
(-3412 1708);
DISPLAY 0.489362 (-3412 1708);
PAINT GREEN (-3412 1708);
FORCEPROP 2 LAST CDS_LIB mstr_standard
J 2
(-3350 1700);
DISPLAY 0.723404 (-3350 1700);
PAINT MONO (-3350 1700);
DISPLAY INVISIBLE (-3350 1700);
FORCEPROP 1 LAST BODY_TYPE PLUMBING
J 0
(-3350 1750);
DISPLAY 0.872340 (-3350 1750);
PAINT GREEN (-3350 1750);
DISPLAY INVISIBLE (-3350 1750);
FORCEPROP 1 LAST HDL_TAP TRUE
J 0
(-3025 1575);
DISPLAY 0.872340 (-3025 1575);
DISPLAY INVISIBLE (-3025 1575);
FORCEPROP 1 LAST PATH I239
J 0
(-3352 1700);
DISPLAY 0.872340 (-3352 1700);
PAINT GREEN (-3352 1700);
DISPLAY INVISIBLE (-3352 1700);
FORCEADD TAP..1
(-3350 1600);
FORCEPROP 3 LASTPIN (-3400 1600) SIG_NAME M_H_CPU1_SB_CB<5>
J 0
(-3390 1610);
DISPLAY 0.659574 (-3390 1610);
PAINT MONO (-3390 1610);
DISPLAY INVISIBLE (-3390 1610);
FORCEPROP 1 LASTPIN (-3400 1600) BN 5
J 0
(-3412 1608);
DISPLAY 0.489362 (-3412 1608);
PAINT GREEN (-3412 1608);
FORCEPROP 2 LAST CDS_LIB mstr_standard
J 2
(-3350 1600);
DISPLAY 0.723404 (-3350 1600);
PAINT MONO (-3350 1600);
DISPLAY INVISIBLE (-3350 1600);
FORCEPROP 1 LAST BODY_TYPE PLUMBING
J 0
(-3350 1650);
DISPLAY 0.872340 (-3350 1650);
PAINT GREEN (-3350 1650);
DISPLAY INVISIBLE (-3350 1650);
FORCEPROP 1 LAST HDL_TAP TRUE
J 0
(-3025 1475);
DISPLAY 0.872340 (-3025 1475);
DISPLAY INVISIBLE (-3025 1475);
FORCEPROP 1 LAST PATH I240
J 0
(-3352 1600);
DISPLAY 0.872340 (-3352 1600);
PAINT GREEN (-3352 1600);
DISPLAY INVISIBLE (-3352 1600);
FORCEADD TAP..1
(-3350 1550);
FORCEPROP 3 LASTPIN (-3400 1550) SIG_NAME M_H_CPU1_SB_CB<6>
J 0
(-3390 1560);
DISPLAY 0.659574 (-3390 1560);
PAINT MONO (-3390 1560);
DISPLAY INVISIBLE (-3390 1560);
FORCEPROP 1 LASTPIN (-3400 1550) BN 6
J 0
(-3412 1558);
DISPLAY 0.489362 (-3412 1558);
PAINT GREEN (-3412 1558);
FORCEPROP 2 LAST CDS_LIB mstr_standard
J 2
(-3350 1550);
DISPLAY 0.723404 (-3350 1550);
PAINT MONO (-3350 1550);
DISPLAY INVISIBLE (-3350 1550);
FORCEPROP 1 LAST BODY_TYPE PLUMBING
J 0
(-3350 1600);
DISPLAY 0.872340 (-3350 1600);
PAINT GREEN (-3350 1600);
DISPLAY INVISIBLE (-3350 1600);
FORCEPROP 1 LAST HDL_TAP TRUE
J 0
(-3025 1425);
DISPLAY 0.872340 (-3025 1425);
DISPLAY INVISIBLE (-3025 1425);
FORCEPROP 1 LAST PATH I241
J 0
(-3352 1550);
DISPLAY 0.872340 (-3352 1550);
PAINT GREEN (-3352 1550);
DISPLAY INVISIBLE (-3352 1550);
FORCEADD TAP..1
(-3350 1650);
FORCEPROP 3 LASTPIN (-3400 1650) SIG_NAME M_H_CPU1_SB_CB<4>
J 0
(-3390 1660);
DISPLAY 0.659574 (-3390 1660);
PAINT MONO (-3390 1660);
DISPLAY INVISIBLE (-3390 1660);
FORCEPROP 1 LASTPIN (-3400 1650) BN 4
J 0
(-3412 1658);
DISPLAY 0.489362 (-3412 1658);
PAINT GREEN (-3412 1658);
FORCEPROP 2 LAST CDS_LIB mstr_standard
J 2
(-3350 1650);
DISPLAY 0.723404 (-3350 1650);
PAINT MONO (-3350 1650);
DISPLAY INVISIBLE (-3350 1650);
FORCEPROP 1 LAST BODY_TYPE PLUMBING
J 0
(-3350 1700);
DISPLAY 0.872340 (-3350 1700);
PAINT GREEN (-3350 1700);
DISPLAY INVISIBLE (-3350 1700);
FORCEPROP 1 LAST HDL_TAP TRUE
J 0
(-3025 1525);
DISPLAY 0.872340 (-3025 1525);
DISPLAY INVISIBLE (-3025 1525);
FORCEPROP 1 LAST PATH I242
J 0
(-3352 1650);
DISPLAY 0.872340 (-3352 1650);
PAINT GREEN (-3352 1650);
DISPLAY INVISIBLE (-3352 1650);
FORCEADD TAP..1
(-3350 1500);
FORCEPROP 3 LASTPIN (-3400 1500) SIG_NAME M_H_CPU1_SB_CB<7>
J 0
(-3390 1510);
DISPLAY 0.659574 (-3390 1510);
PAINT MONO (-3390 1510);
DISPLAY INVISIBLE (-3390 1510);
FORCEPROP 1 LASTPIN (-3400 1500) BN 7
J 0
(-3412 1508);
DISPLAY 0.489362 (-3412 1508);
PAINT GREEN (-3412 1508);
FORCEPROP 2 LAST CDS_LIB mstr_standard
J 2
(-3350 1500);
DISPLAY 0.723404 (-3350 1500);
PAINT MONO (-3350 1500);
DISPLAY INVISIBLE (-3350 1500);
FORCEPROP 1 LAST BODY_TYPE PLUMBING
J 0
(-3350 1550);
DISPLAY 0.872340 (-3350 1550);
PAINT GREEN (-3350 1550);
DISPLAY INVISIBLE (-3350 1550);
FORCEPROP 1 LAST HDL_TAP TRUE
J 0
(-3025 1375);
DISPLAY 0.872340 (-3025 1375);
DISPLAY INVISIBLE (-3025 1375);
FORCEPROP 1 LAST PATH I243
J 0
(-3352 1500);
DISPLAY 0.872340 (-3352 1500);
PAINT GREEN (-3352 1500);
DISPLAY INVISIBLE (-3352 1500);
FORCEADD TAP..1
R 2
(-5775 5900);
FORCEPROP 3 LASTPIN (-5725 5900) SIG_NAME M_H_CPU1_SA_DQS_DP<0>
J 0
(-5715 5910);
DISPLAY 0.659574 (-5715 5910);
PAINT MONO (-5715 5910);
DISPLAY INVISIBLE (-5715 5910);
FORCEPROP 1 LASTPIN (-5725 5900) BN 0
J 2
(-5713 5908);
DISPLAY 0.489362 (-5713 5908);
PAINT GREEN (-5713 5908);
FORCEPROP 2 LAST CDS_LIB mstr_standard
J 2
(-5775 5900);
DISPLAY 0.723404 (-5775 5900);
PAINT MONO (-5775 5900);
DISPLAY INVISIBLE (-5775 5900);
FORCEPROP 1 LAST BODY_TYPE PLUMBING
J 2
(-5775 5950);
DISPLAY 0.872340 (-5775 5950);
PAINT GREEN (-5775 5950);
DISPLAY INVISIBLE (-5775 5950);
FORCEPROP 1 LAST HDL_TAP TRUE
J 2
(-6100 5775);
DISPLAY 0.872340 (-6100 5775);
DISPLAY INVISIBLE (-6100 5775);
FORCEPROP 1 LAST PATH I244
J 2
(-5773 5900);
DISPLAY 0.872340 (-5773 5900);
PAINT GREEN (-5773 5900);
DISPLAY INVISIBLE (-5773 5900);
FORCEADD TAP..1
R 2
(-5775 5800);
FORCEPROP 3 LASTPIN (-5725 5800) SIG_NAME M_H_CPU1_SA_DQS_DP<1>
J 0
(-5715 5810);
DISPLAY 0.659574 (-5715 5810);
PAINT MONO (-5715 5810);
DISPLAY INVISIBLE (-5715 5810);
FORCEPROP 1 LASTPIN (-5725 5800) BN 1
J 2
(-5713 5808);
DISPLAY 0.489362 (-5713 5808);
PAINT GREEN (-5713 5808);
FORCEPROP 2 LAST CDS_LIB mstr_standard
J 2
(-5775 5800);
DISPLAY 0.723404 (-5775 5800);
PAINT MONO (-5775 5800);
DISPLAY INVISIBLE (-5775 5800);
FORCEPROP 1 LAST BODY_TYPE PLUMBING
J 2
(-5775 5850);
DISPLAY 0.872340 (-5775 5850);
PAINT GREEN (-5775 5850);
DISPLAY INVISIBLE (-5775 5850);
FORCEPROP 1 LAST HDL_TAP TRUE
J 2
(-6100 5675);
DISPLAY 0.872340 (-6100 5675);
DISPLAY INVISIBLE (-6100 5675);
FORCEPROP 1 LAST PATH I245
J 2
(-5773 5800);
DISPLAY 0.872340 (-5773 5800);
PAINT GREEN (-5773 5800);
DISPLAY INVISIBLE (-5773 5800);
FORCEADD TAP..1
R 2
(-5775 5700);
FORCEPROP 3 LASTPIN (-5725 5700) SIG_NAME M_H_CPU1_SA_DQS_DP<2>
J 0
(-5715 5710);
DISPLAY 0.659574 (-5715 5710);
PAINT MONO (-5715 5710);
DISPLAY INVISIBLE (-5715 5710);
FORCEPROP 1 LASTPIN (-5725 5700) BN 2
J 2
(-5713 5708);
DISPLAY 0.489362 (-5713 5708);
PAINT GREEN (-5713 5708);
FORCEPROP 2 LAST CDS_LIB mstr_standard
J 2
(-5775 5700);
DISPLAY 0.723404 (-5775 5700);
PAINT MONO (-5775 5700);
DISPLAY INVISIBLE (-5775 5700);
FORCEPROP 1 LAST BODY_TYPE PLUMBING
J 2
(-5775 5750);
DISPLAY 0.872340 (-5775 5750);
PAINT GREEN (-5775 5750);
DISPLAY INVISIBLE (-5775 5750);
FORCEPROP 1 LAST HDL_TAP TRUE
J 2
(-6100 5575);
DISPLAY 0.872340 (-6100 5575);
DISPLAY INVISIBLE (-6100 5575);
FORCEPROP 1 LAST PATH I246
J 2
(-5773 5700);
DISPLAY 0.872340 (-5773 5700);
PAINT GREEN (-5773 5700);
DISPLAY INVISIBLE (-5773 5700);
FORCEADD TAP..1
R 2
(-5975 5650);
FORCEPROP 3 LASTPIN (-5925 5650) SIG_NAME M_H_CPU1_SA_DQS_DN<2>
J 0
(-5915 5660);
DISPLAY 0.659574 (-5915 5660);
PAINT MONO (-5915 5660);
DISPLAY INVISIBLE (-5915 5660);
FORCEPROP 1 LASTPIN (-5925 5650) BN 2
J 2
(-5913 5658);
DISPLAY 0.489362 (-5913 5658);
PAINT GREEN (-5913 5658);
FORCEPROP 2 LAST CDS_LIB mstr_standard
J 2
(-5975 5650);
DISPLAY 0.723404 (-5975 5650);
PAINT MONO (-5975 5650);
DISPLAY INVISIBLE (-5975 5650);
FORCEPROP 1 LAST BODY_TYPE PLUMBING
J 2
(-5975 5700);
DISPLAY 0.872340 (-5975 5700);
PAINT GREEN (-5975 5700);
DISPLAY INVISIBLE (-5975 5700);
FORCEPROP 1 LAST HDL_TAP TRUE
J 2
(-6300 5525);
DISPLAY 0.872340 (-6300 5525);
DISPLAY INVISIBLE (-6300 5525);
FORCEPROP 1 LAST PATH I247
J 2
(-5973 5650);
DISPLAY 0.872340 (-5973 5650);
PAINT GREEN (-5973 5650);
DISPLAY INVISIBLE (-5973 5650);
FORCEADD TAP..1
R 2
(-5975 5750);
FORCEPROP 3 LASTPIN (-5925 5750) SIG_NAME M_H_CPU1_SA_DQS_DN<1>
J 0
(-5915 5760);
DISPLAY 0.659574 (-5915 5760);
PAINT MONO (-5915 5760);
DISPLAY INVISIBLE (-5915 5760);
FORCEPROP 1 LASTPIN (-5925 5750) BN 1
J 2
(-5913 5758);
DISPLAY 0.489362 (-5913 5758);
PAINT GREEN (-5913 5758);
FORCEPROP 2 LAST CDS_LIB mstr_standard
J 2
(-5975 5750);
DISPLAY 0.723404 (-5975 5750);
PAINT MONO (-5975 5750);
DISPLAY INVISIBLE (-5975 5750);
FORCEPROP 1 LAST BODY_TYPE PLUMBING
J 2
(-5975 5800);
DISPLAY 0.872340 (-5975 5800);
PAINT GREEN (-5975 5800);
DISPLAY INVISIBLE (-5975 5800);
FORCEPROP 1 LAST HDL_TAP TRUE
J 2
(-6300 5625);
DISPLAY 0.872340 (-6300 5625);
DISPLAY INVISIBLE (-6300 5625);
FORCEPROP 1 LAST PATH I248
J 2
(-5973 5750);
DISPLAY 0.872340 (-5973 5750);
PAINT GREEN (-5973 5750);
DISPLAY INVISIBLE (-5973 5750);
FORCEADD TAP..1
R 2
(-5975 5850);
FORCEPROP 3 LASTPIN (-5925 5850) SIG_NAME M_H_CPU1_SA_DQS_DN<0>
J 0
(-5915 5860);
DISPLAY 0.659574 (-5915 5860);
PAINT MONO (-5915 5860);
DISPLAY INVISIBLE (-5915 5860);
FORCEPROP 1 LASTPIN (-5925 5850) BN 0
J 2
(-5913 5858);
DISPLAY 0.489362 (-5913 5858);
PAINT GREEN (-5913 5858);
FORCEPROP 2 LAST CDS_LIB mstr_standard
J 2
(-5975 5850);
DISPLAY 0.723404 (-5975 5850);
PAINT MONO (-5975 5850);
DISPLAY INVISIBLE (-5975 5850);
FORCEPROP 1 LAST BODY_TYPE PLUMBING
J 2
(-5975 5900);
DISPLAY 0.872340 (-5975 5900);
PAINT GREEN (-5975 5900);
DISPLAY INVISIBLE (-5975 5900);
FORCEPROP 1 LAST HDL_TAP TRUE
J 2
(-6300 5725);
DISPLAY 0.872340 (-6300 5725);
DISPLAY INVISIBLE (-6300 5725);
FORCEPROP 1 LAST PATH I249
J 2
(-5973 5850);
DISPLAY 0.872340 (-5973 5850);
PAINT GREEN (-5973 5850);
DISPLAY INVISIBLE (-5973 5850);
FORCEADD TAP..1
R 2
(-5775 5600);
FORCEPROP 3 LASTPIN (-5725 5600) SIG_NAME M_H_CPU1_SA_DQS_DP<3>
J 0
(-5715 5610);
DISPLAY 0.659574 (-5715 5610);
PAINT MONO (-5715 5610);
DISPLAY INVISIBLE (-5715 5610);
FORCEPROP 1 LASTPIN (-5725 5600) BN 3
J 2
(-5713 5608);
DISPLAY 0.489362 (-5713 5608);
PAINT GREEN (-5713 5608);
FORCEPROP 2 LAST CDS_LIB mstr_standard
J 2
(-5775 5600);
DISPLAY 0.723404 (-5775 5600);
PAINT MONO (-5775 5600);
DISPLAY INVISIBLE (-5775 5600);
FORCEPROP 1 LAST BODY_TYPE PLUMBING
J 2
(-5775 5650);
DISPLAY 0.872340 (-5775 5650);
PAINT GREEN (-5775 5650);
DISPLAY INVISIBLE (-5775 5650);
FORCEPROP 1 LAST HDL_TAP TRUE
J 2
(-6100 5475);
DISPLAY 0.872340 (-6100 5475);
DISPLAY INVISIBLE (-6100 5475);
FORCEPROP 1 LAST PATH I250
J 2
(-5773 5600);
DISPLAY 0.872340 (-5773 5600);
PAINT GREEN (-5773 5600);
DISPLAY INVISIBLE (-5773 5600);
FORCEADD TAP..1
R 2
(-5775 5500);
FORCEPROP 3 LASTPIN (-5725 5500) SIG_NAME M_H_CPU1_SA_DQS_DP<4>
J 0
(-5715 5510);
DISPLAY 0.659574 (-5715 5510);
PAINT MONO (-5715 5510);
DISPLAY INVISIBLE (-5715 5510);
FORCEPROP 1 LASTPIN (-5725 5500) BN 4
J 2
(-5713 5508);
DISPLAY 0.489362 (-5713 5508);
PAINT GREEN (-5713 5508);
FORCEPROP 2 LAST CDS_LIB mstr_standard
J 2
(-5775 5500);
DISPLAY 0.723404 (-5775 5500);
PAINT MONO (-5775 5500);
DISPLAY INVISIBLE (-5775 5500);
FORCEPROP 1 LAST BODY_TYPE PLUMBING
J 2
(-5775 5550);
DISPLAY 0.872340 (-5775 5550);
PAINT GREEN (-5775 5550);
DISPLAY INVISIBLE (-5775 5550);
FORCEPROP 1 LAST HDL_TAP TRUE
J 2
(-6100 5375);
DISPLAY 0.872340 (-6100 5375);
DISPLAY INVISIBLE (-6100 5375);
FORCEPROP 1 LAST PATH I251
J 2
(-5773 5500);
DISPLAY 0.872340 (-5773 5500);
PAINT GREEN (-5773 5500);
DISPLAY INVISIBLE (-5773 5500);
FORCEADD TAP..1
R 2
(-5775 5400);
FORCEPROP 3 LASTPIN (-5725 5400) SIG_NAME M_H_CPU1_SA_DQS_DP<5>
J 0
(-5715 5410);
DISPLAY 0.659574 (-5715 5410);
PAINT MONO (-5715 5410);
DISPLAY INVISIBLE (-5715 5410);
FORCEPROP 1 LASTPIN (-5725 5400) BN 5
J 2
(-5713 5408);
DISPLAY 0.489362 (-5713 5408);
PAINT GREEN (-5713 5408);
FORCEPROP 2 LAST CDS_LIB mstr_standard
J 2
(-5775 5400);
DISPLAY 0.723404 (-5775 5400);
PAINT MONO (-5775 5400);
DISPLAY INVISIBLE (-5775 5400);
FORCEPROP 1 LAST BODY_TYPE PLUMBING
J 2
(-5775 5450);
DISPLAY 0.872340 (-5775 5450);
PAINT GREEN (-5775 5450);
DISPLAY INVISIBLE (-5775 5450);
FORCEPROP 1 LAST HDL_TAP TRUE
J 2
(-6100 5275);
DISPLAY 0.872340 (-6100 5275);
DISPLAY INVISIBLE (-6100 5275);
FORCEPROP 1 LAST PATH I252
J 2
(-5773 5400);
DISPLAY 0.872340 (-5773 5400);
PAINT GREEN (-5773 5400);
DISPLAY INVISIBLE (-5773 5400);
FORCEADD TAP..1
R 2
(-5775 5300);
FORCEPROP 3 LASTPIN (-5725 5300) SIG_NAME M_H_CPU1_SA_DQS_DP<6>
J 0
(-5715 5310);
DISPLAY 0.659574 (-5715 5310);
PAINT MONO (-5715 5310);
DISPLAY INVISIBLE (-5715 5310);
FORCEPROP 1 LASTPIN (-5725 5300) BN 6
J 2
(-5713 5308);
DISPLAY 0.489362 (-5713 5308);
PAINT GREEN (-5713 5308);
FORCEPROP 2 LAST CDS_LIB mstr_standard
J 2
(-5775 5300);
DISPLAY 0.723404 (-5775 5300);
PAINT MONO (-5775 5300);
DISPLAY INVISIBLE (-5775 5300);
FORCEPROP 1 LAST BODY_TYPE PLUMBING
J 2
(-5775 5350);
DISPLAY 0.872340 (-5775 5350);
PAINT GREEN (-5775 5350);
DISPLAY INVISIBLE (-5775 5350);
FORCEPROP 1 LAST HDL_TAP TRUE
J 2
(-6100 5175);
DISPLAY 0.872340 (-6100 5175);
DISPLAY INVISIBLE (-6100 5175);
FORCEPROP 1 LAST PATH I253
J 2
(-5773 5300);
DISPLAY 0.872340 (-5773 5300);
PAINT GREEN (-5773 5300);
DISPLAY INVISIBLE (-5773 5300);
FORCEADD TAP..1
R 2
(-5775 5200);
FORCEPROP 3 LASTPIN (-5725 5200) SIG_NAME M_H_CPU1_SA_DQS_DP<7>
J 0
(-5715 5210);
DISPLAY 0.659574 (-5715 5210);
PAINT MONO (-5715 5210);
DISPLAY INVISIBLE (-5715 5210);
FORCEPROP 1 LASTPIN (-5725 5200) BN 7
J 2
(-5713 5208);
DISPLAY 0.489362 (-5713 5208);
PAINT GREEN (-5713 5208);
FORCEPROP 2 LAST CDS_LIB mstr_standard
J 2
(-5775 5200);
DISPLAY 0.723404 (-5775 5200);
PAINT MONO (-5775 5200);
DISPLAY INVISIBLE (-5775 5200);
FORCEPROP 1 LAST BODY_TYPE PLUMBING
J 2
(-5775 5250);
DISPLAY 0.872340 (-5775 5250);
PAINT GREEN (-5775 5250);
DISPLAY INVISIBLE (-5775 5250);
FORCEPROP 1 LAST HDL_TAP TRUE
J 2
(-6100 5075);
DISPLAY 0.872340 (-6100 5075);
DISPLAY INVISIBLE (-6100 5075);
FORCEPROP 1 LAST PATH I254
J 2
(-5773 5200);
DISPLAY 0.872340 (-5773 5200);
PAINT GREEN (-5773 5200);
DISPLAY INVISIBLE (-5773 5200);
FORCEADD TAP..1
R 2
(-5975 5550);
FORCEPROP 3 LASTPIN (-5925 5550) SIG_NAME M_H_CPU1_SA_DQS_DN<3>
J 0
(-5915 5560);
DISPLAY 0.659574 (-5915 5560);
PAINT MONO (-5915 5560);
DISPLAY INVISIBLE (-5915 5560);
FORCEPROP 1 LASTPIN (-5925 5550) BN 3
J 2
(-5913 5558);
DISPLAY 0.489362 (-5913 5558);
PAINT GREEN (-5913 5558);
FORCEPROP 2 LAST CDS_LIB mstr_standard
J 2
(-5975 5550);
DISPLAY 0.723404 (-5975 5550);
PAINT MONO (-5975 5550);
DISPLAY INVISIBLE (-5975 5550);
FORCEPROP 1 LAST BODY_TYPE PLUMBING
J 2
(-5975 5600);
DISPLAY 0.872340 (-5975 5600);
PAINT GREEN (-5975 5600);
DISPLAY INVISIBLE (-5975 5600);
FORCEPROP 1 LAST HDL_TAP TRUE
J 2
(-6300 5425);
DISPLAY 0.872340 (-6300 5425);
DISPLAY INVISIBLE (-6300 5425);
FORCEPROP 1 LAST PATH I255
J 2
(-5973 5550);
DISPLAY 0.872340 (-5973 5550);
PAINT GREEN (-5973 5550);
DISPLAY INVISIBLE (-5973 5550);
FORCEADD TAP..1
R 2
(-5975 5450);
FORCEPROP 3 LASTPIN (-5925 5450) SIG_NAME M_H_CPU1_SA_DQS_DN<4>
J 0
(-5915 5460);
DISPLAY 0.659574 (-5915 5460);
PAINT MONO (-5915 5460);
DISPLAY INVISIBLE (-5915 5460);
FORCEPROP 1 LASTPIN (-5925 5450) BN 4
J 2
(-5913 5458);
DISPLAY 0.489362 (-5913 5458);
PAINT GREEN (-5913 5458);
FORCEPROP 2 LAST CDS_LIB mstr_standard
J 2
(-5975 5450);
DISPLAY 0.723404 (-5975 5450);
PAINT MONO (-5975 5450);
DISPLAY INVISIBLE (-5975 5450);
FORCEPROP 1 LAST BODY_TYPE PLUMBING
J 2
(-5975 5500);
DISPLAY 0.872340 (-5975 5500);
PAINT GREEN (-5975 5500);
DISPLAY INVISIBLE (-5975 5500);
FORCEPROP 1 LAST HDL_TAP TRUE
J 2
(-6300 5325);
DISPLAY 0.872340 (-6300 5325);
DISPLAY INVISIBLE (-6300 5325);
FORCEPROP 1 LAST PATH I256
J 2
(-5973 5450);
DISPLAY 0.872340 (-5973 5450);
PAINT GREEN (-5973 5450);
DISPLAY INVISIBLE (-5973 5450);
FORCEADD TAP..1
R 2
(-5975 5350);
FORCEPROP 3 LASTPIN (-5925 5350) SIG_NAME M_H_CPU1_SA_DQS_DN<5>
J 0
(-5915 5360);
DISPLAY 0.659574 (-5915 5360);
PAINT MONO (-5915 5360);
DISPLAY INVISIBLE (-5915 5360);
FORCEPROP 1 LASTPIN (-5925 5350) BN 5
J 2
(-5913 5358);
DISPLAY 0.489362 (-5913 5358);
PAINT GREEN (-5913 5358);
FORCEPROP 2 LAST CDS_LIB mstr_standard
J 2
(-5975 5350);
DISPLAY 0.723404 (-5975 5350);
PAINT MONO (-5975 5350);
DISPLAY INVISIBLE (-5975 5350);
FORCEPROP 1 LAST BODY_TYPE PLUMBING
J 2
(-5975 5400);
DISPLAY 0.872340 (-5975 5400);
PAINT GREEN (-5975 5400);
DISPLAY INVISIBLE (-5975 5400);
FORCEPROP 1 LAST HDL_TAP TRUE
J 2
(-6300 5225);
DISPLAY 0.872340 (-6300 5225);
DISPLAY INVISIBLE (-6300 5225);
FORCEPROP 1 LAST PATH I257
J 2
(-5973 5350);
DISPLAY 0.872340 (-5973 5350);
PAINT GREEN (-5973 5350);
DISPLAY INVISIBLE (-5973 5350);
FORCEADD TAP..1
R 2
(-5975 5250);
FORCEPROP 3 LASTPIN (-5925 5250) SIG_NAME M_H_CPU1_SA_DQS_DN<6>
J 0
(-5915 5260);
DISPLAY 0.659574 (-5915 5260);
PAINT MONO (-5915 5260);
DISPLAY INVISIBLE (-5915 5260);
FORCEPROP 1 LASTPIN (-5925 5250) BN 6
J 2
(-5913 5258);
DISPLAY 0.489362 (-5913 5258);
PAINT GREEN (-5913 5258);
FORCEPROP 2 LAST CDS_LIB mstr_standard
J 2
(-5975 5250);
DISPLAY 0.723404 (-5975 5250);
PAINT MONO (-5975 5250);
DISPLAY INVISIBLE (-5975 5250);
FORCEPROP 1 LAST BODY_TYPE PLUMBING
J 2
(-5975 5300);
DISPLAY 0.872340 (-5975 5300);
PAINT GREEN (-5975 5300);
DISPLAY INVISIBLE (-5975 5300);
FORCEPROP 1 LAST HDL_TAP TRUE
J 2
(-6300 5125);
DISPLAY 0.872340 (-6300 5125);
DISPLAY INVISIBLE (-6300 5125);
FORCEPROP 1 LAST PATH I258
J 2
(-5973 5250);
DISPLAY 0.872340 (-5973 5250);
PAINT GREEN (-5973 5250);
DISPLAY INVISIBLE (-5973 5250);
FORCEADD TAP..1
R 2
(-5975 5150);
FORCEPROP 3 LASTPIN (-5925 5150) SIG_NAME M_H_CPU1_SA_DQS_DN<7>
J 0
(-5915 5160);
DISPLAY 0.659574 (-5915 5160);
PAINT MONO (-5915 5160);
DISPLAY INVISIBLE (-5915 5160);
FORCEPROP 1 LASTPIN (-5925 5150) BN 7
J 2
(-5913 5158);
DISPLAY 0.489362 (-5913 5158);
PAINT GREEN (-5913 5158);
FORCEPROP 2 LAST CDS_LIB mstr_standard
J 2
(-5975 5150);
DISPLAY 0.723404 (-5975 5150);
PAINT MONO (-5975 5150);
DISPLAY INVISIBLE (-5975 5150);
FORCEPROP 1 LAST BODY_TYPE PLUMBING
J 2
(-5975 5200);
DISPLAY 0.872340 (-5975 5200);
PAINT GREEN (-5975 5200);
DISPLAY INVISIBLE (-5975 5200);
FORCEPROP 1 LAST HDL_TAP TRUE
J 2
(-6300 5025);
DISPLAY 0.872340 (-6300 5025);
DISPLAY INVISIBLE (-6300 5025);
FORCEPROP 1 LAST PATH I259
J 2
(-5973 5150);
DISPLAY 0.872340 (-5973 5150);
PAINT GREEN (-5973 5150);
DISPLAY INVISIBLE (-5973 5150);
FORCEADD TAP..1
R 2
(-5775 5100);
FORCEPROP 3 LASTPIN (-5725 5100) SIG_NAME M_H_CPU1_SA_DQS_DP<8>
J 0
(-5715 5110);
DISPLAY 0.659574 (-5715 5110);
PAINT MONO (-5715 5110);
DISPLAY INVISIBLE (-5715 5110);
FORCEPROP 1 LASTPIN (-5725 5100) BN 8
J 2
(-5713 5108);
DISPLAY 0.489362 (-5713 5108);
PAINT GREEN (-5713 5108);
FORCEPROP 2 LAST CDS_LIB mstr_standard
J 2
(-5775 5100);
DISPLAY 0.723404 (-5775 5100);
PAINT MONO (-5775 5100);
DISPLAY INVISIBLE (-5775 5100);
FORCEPROP 1 LAST BODY_TYPE PLUMBING
J 2
(-5775 5150);
DISPLAY 0.872340 (-5775 5150);
PAINT GREEN (-5775 5150);
DISPLAY INVISIBLE (-5775 5150);
FORCEPROP 1 LAST HDL_TAP TRUE
J 2
(-6100 4975);
DISPLAY 0.872340 (-6100 4975);
DISPLAY INVISIBLE (-6100 4975);
FORCEPROP 1 LAST PATH I260
J 2
(-5773 5100);
DISPLAY 0.872340 (-5773 5100);
PAINT GREEN (-5773 5100);
DISPLAY INVISIBLE (-5773 5100);
FORCEADD TAP..1
R 2
(-5775 5000);
FORCEPROP 3 LASTPIN (-5725 5000) SIG_NAME M_H_CPU1_SA_DQS_DP<9>
J 0
(-5715 5010);
DISPLAY 0.659574 (-5715 5010);
PAINT MONO (-5715 5010);
DISPLAY INVISIBLE (-5715 5010);
FORCEPROP 1 LASTPIN (-5725 5000) BN 9
J 2
(-5713 5008);
DISPLAY 0.489362 (-5713 5008);
PAINT GREEN (-5713 5008);
FORCEPROP 2 LAST CDS_LIB mstr_standard
J 2
(-5775 5000);
DISPLAY 0.723404 (-5775 5000);
PAINT MONO (-5775 5000);
DISPLAY INVISIBLE (-5775 5000);
FORCEPROP 1 LAST BODY_TYPE PLUMBING
J 2
(-5775 5050);
DISPLAY 0.872340 (-5775 5050);
PAINT GREEN (-5775 5050);
DISPLAY INVISIBLE (-5775 5050);
FORCEPROP 1 LAST HDL_TAP TRUE
J 2
(-6100 4875);
DISPLAY 0.872340 (-6100 4875);
DISPLAY INVISIBLE (-6100 4875);
FORCEPROP 1 LAST PATH I261
J 2
(-5773 5000);
DISPLAY 0.872340 (-5773 5000);
PAINT GREEN (-5773 5000);
DISPLAY INVISIBLE (-5773 5000);
FORCEADD TAP..1
R 2
(-5775 4850);
FORCEPROP 3 LASTPIN (-5725 4850) SIG_NAME M_H_CPU1_SB_DQS_DP<0>
J 0
(-5715 4860);
DISPLAY 0.659574 (-5715 4860);
PAINT MONO (-5715 4860);
DISPLAY INVISIBLE (-5715 4860);
FORCEPROP 1 LASTPIN (-5725 4850) BN 0
J 2
(-5713 4858);
DISPLAY 0.489362 (-5713 4858);
PAINT GREEN (-5713 4858);
FORCEPROP 2 LAST CDS_LIB mstr_standard
J 2
(-5775 4850);
DISPLAY 0.723404 (-5775 4850);
PAINT MONO (-5775 4850);
DISPLAY INVISIBLE (-5775 4850);
FORCEPROP 1 LAST BODY_TYPE PLUMBING
J 2
(-5775 4900);
DISPLAY 0.872340 (-5775 4900);
PAINT GREEN (-5775 4900);
DISPLAY INVISIBLE (-5775 4900);
FORCEPROP 1 LAST HDL_TAP TRUE
J 2
(-6100 4725);
DISPLAY 0.872340 (-6100 4725);
DISPLAY INVISIBLE (-6100 4725);
FORCEPROP 1 LAST PATH I262
J 2
(-5773 4850);
DISPLAY 0.872340 (-5773 4850);
PAINT GREEN (-5773 4850);
DISPLAY INVISIBLE (-5773 4850);
FORCEADD TAP..1
R 2
(-5775 4750);
FORCEPROP 3 LASTPIN (-5725 4750) SIG_NAME M_H_CPU1_SB_DQS_DP<1>
J 0
(-5715 4760);
DISPLAY 0.659574 (-5715 4760);
PAINT MONO (-5715 4760);
DISPLAY INVISIBLE (-5715 4760);
FORCEPROP 1 LASTPIN (-5725 4750) BN 1
J 2
(-5713 4758);
DISPLAY 0.489362 (-5713 4758);
PAINT GREEN (-5713 4758);
FORCEPROP 2 LAST CDS_LIB mstr_standard
J 2
(-5775 4750);
DISPLAY 0.723404 (-5775 4750);
PAINT MONO (-5775 4750);
DISPLAY INVISIBLE (-5775 4750);
FORCEPROP 1 LAST BODY_TYPE PLUMBING
J 2
(-5775 4800);
DISPLAY 0.872340 (-5775 4800);
PAINT GREEN (-5775 4800);
DISPLAY INVISIBLE (-5775 4800);
FORCEPROP 1 LAST HDL_TAP TRUE
J 2
(-6100 4625);
DISPLAY 0.872340 (-6100 4625);
DISPLAY INVISIBLE (-6100 4625);
FORCEPROP 1 LAST PATH I263
J 2
(-5773 4750);
DISPLAY 0.872340 (-5773 4750);
PAINT GREEN (-5773 4750);
DISPLAY INVISIBLE (-5773 4750);
FORCEADD TAP..1
R 2
(-5775 4650);
FORCEPROP 3 LASTPIN (-5725 4650) SIG_NAME M_H_CPU1_SB_DQS_DP<2>
J 0
(-5715 4660);
DISPLAY 0.659574 (-5715 4660);
PAINT MONO (-5715 4660);
DISPLAY INVISIBLE (-5715 4660);
FORCEPROP 1 LASTPIN (-5725 4650) BN 2
J 2
(-5713 4658);
DISPLAY 0.489362 (-5713 4658);
PAINT GREEN (-5713 4658);
FORCEPROP 2 LAST CDS_LIB mstr_standard
J 2
(-5775 4650);
DISPLAY 0.723404 (-5775 4650);
PAINT MONO (-5775 4650);
DISPLAY INVISIBLE (-5775 4650);
FORCEPROP 1 LAST BODY_TYPE PLUMBING
J 2
(-5775 4700);
DISPLAY 0.872340 (-5775 4700);
PAINT GREEN (-5775 4700);
DISPLAY INVISIBLE (-5775 4700);
FORCEPROP 1 LAST HDL_TAP TRUE
J 2
(-6100 4525);
DISPLAY 0.872340 (-6100 4525);
DISPLAY INVISIBLE (-6100 4525);
FORCEPROP 1 LAST PATH I264
J 2
(-5773 4650);
DISPLAY 0.872340 (-5773 4650);
PAINT GREEN (-5773 4650);
DISPLAY INVISIBLE (-5773 4650);
FORCEADD TAP..1
R 2
(-5975 5050);
FORCEPROP 3 LASTPIN (-5925 5050) SIG_NAME M_H_CPU1_SA_DQS_DN<8>
J 0
(-5915 5060);
DISPLAY 0.659574 (-5915 5060);
PAINT MONO (-5915 5060);
DISPLAY INVISIBLE (-5915 5060);
FORCEPROP 1 LASTPIN (-5925 5050) BN 8
J 2
(-5913 5058);
DISPLAY 0.489362 (-5913 5058);
PAINT GREEN (-5913 5058);
FORCEPROP 2 LAST CDS_LIB mstr_standard
J 2
(-5975 5050);
DISPLAY 0.723404 (-5975 5050);
PAINT MONO (-5975 5050);
DISPLAY INVISIBLE (-5975 5050);
FORCEPROP 1 LAST BODY_TYPE PLUMBING
J 2
(-5975 5100);
DISPLAY 0.872340 (-5975 5100);
PAINT GREEN (-5975 5100);
DISPLAY INVISIBLE (-5975 5100);
FORCEPROP 1 LAST HDL_TAP TRUE
J 2
(-6300 4925);
DISPLAY 0.872340 (-6300 4925);
DISPLAY INVISIBLE (-6300 4925);
FORCEPROP 1 LAST PATH I265
J 2
(-5973 5050);
DISPLAY 0.872340 (-5973 5050);
PAINT GREEN (-5973 5050);
DISPLAY INVISIBLE (-5973 5050);
FORCEADD TAP..1
R 2
(-5975 4950);
FORCEPROP 3 LASTPIN (-5925 4950) SIG_NAME M_H_CPU1_SA_DQS_DN<9>
J 0
(-5915 4960);
DISPLAY 0.659574 (-5915 4960);
PAINT MONO (-5915 4960);
DISPLAY INVISIBLE (-5915 4960);
FORCEPROP 1 LASTPIN (-5925 4950) BN 9
J 2
(-5913 4958);
DISPLAY 0.489362 (-5913 4958);
PAINT GREEN (-5913 4958);
FORCEPROP 2 LAST CDS_LIB mstr_standard
J 2
(-5975 4950);
DISPLAY 0.723404 (-5975 4950);
PAINT MONO (-5975 4950);
DISPLAY INVISIBLE (-5975 4950);
FORCEPROP 1 LAST BODY_TYPE PLUMBING
J 2
(-5975 5000);
DISPLAY 0.872340 (-5975 5000);
PAINT GREEN (-5975 5000);
DISPLAY INVISIBLE (-5975 5000);
FORCEPROP 1 LAST HDL_TAP TRUE
J 2
(-6300 4825);
DISPLAY 0.872340 (-6300 4825);
DISPLAY INVISIBLE (-6300 4825);
FORCEPROP 1 LAST PATH I266
J 2
(-5973 4950);
DISPLAY 0.872340 (-5973 4950);
PAINT GREEN (-5973 4950);
DISPLAY INVISIBLE (-5973 4950);
FORCEADD TAP..1
R 2
(-5975 4800);
FORCEPROP 3 LASTPIN (-5925 4800) SIG_NAME M_H_CPU1_SB_DQS_DN<0>
J 0
(-5915 4810);
DISPLAY 0.659574 (-5915 4810);
PAINT MONO (-5915 4810);
DISPLAY INVISIBLE (-5915 4810);
FORCEPROP 1 LASTPIN (-5925 4800) BN 0
J 2
(-5913 4808);
DISPLAY 0.489362 (-5913 4808);
PAINT GREEN (-5913 4808);
FORCEPROP 2 LAST CDS_LIB mstr_standard
J 2
(-5975 4800);
DISPLAY 0.723404 (-5975 4800);
PAINT MONO (-5975 4800);
DISPLAY INVISIBLE (-5975 4800);
FORCEPROP 1 LAST BODY_TYPE PLUMBING
J 2
(-5975 4850);
DISPLAY 0.872340 (-5975 4850);
PAINT GREEN (-5975 4850);
DISPLAY INVISIBLE (-5975 4850);
FORCEPROP 1 LAST HDL_TAP TRUE
J 2
(-6300 4675);
DISPLAY 0.872340 (-6300 4675);
DISPLAY INVISIBLE (-6300 4675);
FORCEPROP 1 LAST PATH I267
J 2
(-5973 4800);
DISPLAY 0.872340 (-5973 4800);
PAINT GREEN (-5973 4800);
DISPLAY INVISIBLE (-5973 4800);
FORCEADD TAP..1
R 2
(-5975 4700);
FORCEPROP 3 LASTPIN (-5925 4700) SIG_NAME M_H_CPU1_SB_DQS_DN<1>
J 0
(-5915 4710);
DISPLAY 0.659574 (-5915 4710);
PAINT MONO (-5915 4710);
DISPLAY INVISIBLE (-5915 4710);
FORCEPROP 1 LASTPIN (-5925 4700) BN 1
J 2
(-5913 4708);
DISPLAY 0.489362 (-5913 4708);
PAINT GREEN (-5913 4708);
FORCEPROP 2 LAST CDS_LIB mstr_standard
J 2
(-5975 4700);
DISPLAY 0.723404 (-5975 4700);
PAINT MONO (-5975 4700);
DISPLAY INVISIBLE (-5975 4700);
FORCEPROP 1 LAST BODY_TYPE PLUMBING
J 2
(-5975 4750);
DISPLAY 0.872340 (-5975 4750);
PAINT GREEN (-5975 4750);
DISPLAY INVISIBLE (-5975 4750);
FORCEPROP 1 LAST HDL_TAP TRUE
J 2
(-6300 4575);
DISPLAY 0.872340 (-6300 4575);
DISPLAY INVISIBLE (-6300 4575);
FORCEPROP 1 LAST PATH I268
J 2
(-5973 4700);
DISPLAY 0.872340 (-5973 4700);
PAINT GREEN (-5973 4700);
DISPLAY INVISIBLE (-5973 4700);
FORCEADD TAP..1
R 2
(-5775 4550);
FORCEPROP 3 LASTPIN (-5725 4550) SIG_NAME M_H_CPU1_SB_DQS_DP<3>
J 0
(-5715 4560);
DISPLAY 0.659574 (-5715 4560);
PAINT MONO (-5715 4560);
DISPLAY INVISIBLE (-5715 4560);
FORCEPROP 1 LASTPIN (-5725 4550) BN 3
J 2
(-5713 4558);
DISPLAY 0.489362 (-5713 4558);
PAINT GREEN (-5713 4558);
FORCEPROP 2 LAST CDS_LIB mstr_standard
J 2
(-5775 4550);
DISPLAY 0.723404 (-5775 4550);
PAINT MONO (-5775 4550);
DISPLAY INVISIBLE (-5775 4550);
FORCEPROP 1 LAST BODY_TYPE PLUMBING
J 2
(-5775 4600);
DISPLAY 0.872340 (-5775 4600);
PAINT GREEN (-5775 4600);
DISPLAY INVISIBLE (-5775 4600);
FORCEPROP 1 LAST HDL_TAP TRUE
J 2
(-6100 4425);
DISPLAY 0.872340 (-6100 4425);
DISPLAY INVISIBLE (-6100 4425);
FORCEPROP 1 LAST PATH I269
J 2
(-5773 4550);
DISPLAY 0.872340 (-5773 4550);
PAINT GREEN (-5773 4550);
DISPLAY INVISIBLE (-5773 4550);
FORCEADD TAP..1
R 2
(-5775 4450);
FORCEPROP 3 LASTPIN (-5725 4450) SIG_NAME M_H_CPU1_SB_DQS_DP<4>
J 0
(-5715 4460);
DISPLAY 0.659574 (-5715 4460);
PAINT MONO (-5715 4460);
DISPLAY INVISIBLE (-5715 4460);
FORCEPROP 1 LASTPIN (-5725 4450) BN 4
J 2
(-5713 4458);
DISPLAY 0.489362 (-5713 4458);
PAINT GREEN (-5713 4458);
FORCEPROP 2 LAST CDS_LIB mstr_standard
J 2
(-5775 4450);
DISPLAY 0.723404 (-5775 4450);
PAINT MONO (-5775 4450);
DISPLAY INVISIBLE (-5775 4450);
FORCEPROP 1 LAST BODY_TYPE PLUMBING
J 2
(-5775 4500);
DISPLAY 0.872340 (-5775 4500);
PAINT GREEN (-5775 4500);
DISPLAY INVISIBLE (-5775 4500);
FORCEPROP 1 LAST HDL_TAP TRUE
J 2
(-6100 4325);
DISPLAY 0.872340 (-6100 4325);
DISPLAY INVISIBLE (-6100 4325);
FORCEPROP 1 LAST PATH I270
J 2
(-5773 4450);
DISPLAY 0.872340 (-5773 4450);
PAINT GREEN (-5773 4450);
DISPLAY INVISIBLE (-5773 4450);
FORCEADD TAP..1
R 2
(-5975 4600);
FORCEPROP 3 LASTPIN (-5925 4600) SIG_NAME M_H_CPU1_SB_DQS_DN<2>
J 0
(-5915 4610);
DISPLAY 0.659574 (-5915 4610);
PAINT MONO (-5915 4610);
DISPLAY INVISIBLE (-5915 4610);
FORCEPROP 1 LASTPIN (-5925 4600) BN 2
J 2
(-5913 4608);
DISPLAY 0.489362 (-5913 4608);
PAINT GREEN (-5913 4608);
FORCEPROP 2 LAST CDS_LIB mstr_standard
J 2
(-5975 4600);
DISPLAY 0.723404 (-5975 4600);
PAINT MONO (-5975 4600);
DISPLAY INVISIBLE (-5975 4600);
FORCEPROP 1 LAST BODY_TYPE PLUMBING
J 2
(-5975 4650);
DISPLAY 0.872340 (-5975 4650);
PAINT GREEN (-5975 4650);
DISPLAY INVISIBLE (-5975 4650);
FORCEPROP 1 LAST HDL_TAP TRUE
J 2
(-6300 4475);
DISPLAY 0.872340 (-6300 4475);
DISPLAY INVISIBLE (-6300 4475);
FORCEPROP 1 LAST PATH I271
J 2
(-5973 4600);
DISPLAY 0.872340 (-5973 4600);
PAINT GREEN (-5973 4600);
DISPLAY INVISIBLE (-5973 4600);
FORCEADD TAP..1
R 2
(-5775 4350);
FORCEPROP 3 LASTPIN (-5725 4350) SIG_NAME M_H_CPU1_SB_DQS_DP<5>
J 0
(-5715 4360);
DISPLAY 0.659574 (-5715 4360);
PAINT MONO (-5715 4360);
DISPLAY INVISIBLE (-5715 4360);
FORCEPROP 1 LASTPIN (-5725 4350) BN 5
J 2
(-5713 4358);
DISPLAY 0.489362 (-5713 4358);
PAINT GREEN (-5713 4358);
FORCEPROP 2 LAST CDS_LIB mstr_standard
J 2
(-5775 4350);
DISPLAY 0.723404 (-5775 4350);
PAINT MONO (-5775 4350);
DISPLAY INVISIBLE (-5775 4350);
FORCEPROP 1 LAST BODY_TYPE PLUMBING
J 2
(-5775 4400);
DISPLAY 0.872340 (-5775 4400);
PAINT GREEN (-5775 4400);
DISPLAY INVISIBLE (-5775 4400);
FORCEPROP 1 LAST HDL_TAP TRUE
J 2
(-6100 4225);
DISPLAY 0.872340 (-6100 4225);
DISPLAY INVISIBLE (-6100 4225);
FORCEPROP 1 LAST PATH I272
J 2
(-5773 4350);
DISPLAY 0.872340 (-5773 4350);
PAINT GREEN (-5773 4350);
DISPLAY INVISIBLE (-5773 4350);
FORCEADD TAP..1
R 2
(-5775 4250);
FORCEPROP 3 LASTPIN (-5725 4250) SIG_NAME M_H_CPU1_SB_DQS_DP<6>
J 0
(-5715 4260);
DISPLAY 0.659574 (-5715 4260);
PAINT MONO (-5715 4260);
DISPLAY INVISIBLE (-5715 4260);
FORCEPROP 1 LASTPIN (-5725 4250) BN 6
J 2
(-5713 4258);
DISPLAY 0.489362 (-5713 4258);
PAINT GREEN (-5713 4258);
FORCEPROP 2 LAST CDS_LIB mstr_standard
J 2
(-5775 4250);
DISPLAY 0.723404 (-5775 4250);
PAINT MONO (-5775 4250);
DISPLAY INVISIBLE (-5775 4250);
FORCEPROP 1 LAST BODY_TYPE PLUMBING
J 2
(-5775 4300);
DISPLAY 0.872340 (-5775 4300);
PAINT GREEN (-5775 4300);
DISPLAY INVISIBLE (-5775 4300);
FORCEPROP 1 LAST HDL_TAP TRUE
J 2
(-6100 4125);
DISPLAY 0.872340 (-6100 4125);
DISPLAY INVISIBLE (-6100 4125);
FORCEPROP 1 LAST PATH I273
J 2
(-5773 4250);
DISPLAY 0.872340 (-5773 4250);
PAINT GREEN (-5773 4250);
DISPLAY INVISIBLE (-5773 4250);
FORCEADD TAP..1
R 2
(-5775 4150);
FORCEPROP 3 LASTPIN (-5725 4150) SIG_NAME M_H_CPU1_SB_DQS_DP<7>
J 0
(-5715 4160);
DISPLAY 0.659574 (-5715 4160);
PAINT MONO (-5715 4160);
DISPLAY INVISIBLE (-5715 4160);
FORCEPROP 1 LASTPIN (-5725 4150) BN 7
J 2
(-5713 4158);
DISPLAY 0.489362 (-5713 4158);
PAINT GREEN (-5713 4158);
FORCEPROP 2 LAST CDS_LIB mstr_standard
J 2
(-5775 4150);
DISPLAY 0.723404 (-5775 4150);
PAINT MONO (-5775 4150);
DISPLAY INVISIBLE (-5775 4150);
FORCEPROP 1 LAST BODY_TYPE PLUMBING
J 2
(-5775 4200);
DISPLAY 0.872340 (-5775 4200);
PAINT GREEN (-5775 4200);
DISPLAY INVISIBLE (-5775 4200);
FORCEPROP 1 LAST HDL_TAP TRUE
J 2
(-6100 4025);
DISPLAY 0.872340 (-6100 4025);
DISPLAY INVISIBLE (-6100 4025);
FORCEPROP 1 LAST PATH I274
J 2
(-5773 4150);
DISPLAY 0.872340 (-5773 4150);
PAINT GREEN (-5773 4150);
DISPLAY INVISIBLE (-5773 4150);
FORCEADD TAP..1
R 2
(-5975 4500);
FORCEPROP 3 LASTPIN (-5925 4500) SIG_NAME M_H_CPU1_SB_DQS_DN<3>
J 0
(-5915 4510);
DISPLAY 0.659574 (-5915 4510);
PAINT MONO (-5915 4510);
DISPLAY INVISIBLE (-5915 4510);
FORCEPROP 1 LASTPIN (-5925 4500) BN 3
J 2
(-5913 4508);
DISPLAY 0.489362 (-5913 4508);
PAINT GREEN (-5913 4508);
FORCEPROP 2 LAST CDS_LIB mstr_standard
J 2
(-5975 4500);
DISPLAY 0.723404 (-5975 4500);
PAINT MONO (-5975 4500);
DISPLAY INVISIBLE (-5975 4500);
FORCEPROP 1 LAST BODY_TYPE PLUMBING
J 2
(-5975 4550);
DISPLAY 0.872340 (-5975 4550);
PAINT GREEN (-5975 4550);
DISPLAY INVISIBLE (-5975 4550);
FORCEPROP 1 LAST HDL_TAP TRUE
J 2
(-6300 4375);
DISPLAY 0.872340 (-6300 4375);
DISPLAY INVISIBLE (-6300 4375);
FORCEPROP 1 LAST PATH I275
J 2
(-5973 4500);
DISPLAY 0.872340 (-5973 4500);
PAINT GREEN (-5973 4500);
DISPLAY INVISIBLE (-5973 4500);
FORCEADD TAP..1
R 2
(-5975 4400);
FORCEPROP 3 LASTPIN (-5925 4400) SIG_NAME M_H_CPU1_SB_DQS_DN<4>
J 0
(-5915 4410);
DISPLAY 0.659574 (-5915 4410);
PAINT MONO (-5915 4410);
DISPLAY INVISIBLE (-5915 4410);
FORCEPROP 1 LASTPIN (-5925 4400) BN 4
J 2
(-5913 4408);
DISPLAY 0.489362 (-5913 4408);
PAINT GREEN (-5913 4408);
FORCEPROP 2 LAST CDS_LIB mstr_standard
J 2
(-5975 4400);
DISPLAY 0.723404 (-5975 4400);
PAINT MONO (-5975 4400);
DISPLAY INVISIBLE (-5975 4400);
FORCEPROP 1 LAST BODY_TYPE PLUMBING
J 2
(-5975 4450);
DISPLAY 0.872340 (-5975 4450);
PAINT GREEN (-5975 4450);
DISPLAY INVISIBLE (-5975 4450);
FORCEPROP 1 LAST HDL_TAP TRUE
J 2
(-6300 4275);
DISPLAY 0.872340 (-6300 4275);
DISPLAY INVISIBLE (-6300 4275);
FORCEPROP 1 LAST PATH I276
J 2
(-5973 4400);
DISPLAY 0.872340 (-5973 4400);
PAINT GREEN (-5973 4400);
DISPLAY INVISIBLE (-5973 4400);
FORCEADD TAP..1
R 2
(-5975 4300);
FORCEPROP 3 LASTPIN (-5925 4300) SIG_NAME M_H_CPU1_SB_DQS_DN<5>
J 0
(-5915 4310);
DISPLAY 0.659574 (-5915 4310);
PAINT MONO (-5915 4310);
DISPLAY INVISIBLE (-5915 4310);
FORCEPROP 1 LASTPIN (-5925 4300) BN 5
J 2
(-5913 4308);
DISPLAY 0.489362 (-5913 4308);
PAINT GREEN (-5913 4308);
FORCEPROP 2 LAST CDS_LIB mstr_standard
J 2
(-5975 4300);
DISPLAY 0.723404 (-5975 4300);
PAINT MONO (-5975 4300);
DISPLAY INVISIBLE (-5975 4300);
FORCEPROP 1 LAST BODY_TYPE PLUMBING
J 2
(-5975 4350);
DISPLAY 0.872340 (-5975 4350);
PAINT GREEN (-5975 4350);
DISPLAY INVISIBLE (-5975 4350);
FORCEPROP 1 LAST HDL_TAP TRUE
J 2
(-6300 4175);
DISPLAY 0.872340 (-6300 4175);
DISPLAY INVISIBLE (-6300 4175);
FORCEPROP 1 LAST PATH I277
J 2
(-5973 4300);
DISPLAY 0.872340 (-5973 4300);
PAINT GREEN (-5973 4300);
DISPLAY INVISIBLE (-5973 4300);
FORCEADD TAP..1
R 2
(-5975 4200);
FORCEPROP 3 LASTPIN (-5925 4200) SIG_NAME M_H_CPU1_SB_DQS_DN<6>
J 0
(-5915 4210);
DISPLAY 0.659574 (-5915 4210);
PAINT MONO (-5915 4210);
DISPLAY INVISIBLE (-5915 4210);
FORCEPROP 1 LASTPIN (-5925 4200) BN 6
J 2
(-5913 4208);
DISPLAY 0.489362 (-5913 4208);
PAINT GREEN (-5913 4208);
FORCEPROP 2 LAST CDS_LIB mstr_standard
J 2
(-5975 4200);
DISPLAY 0.723404 (-5975 4200);
PAINT MONO (-5975 4200);
DISPLAY INVISIBLE (-5975 4200);
FORCEPROP 1 LAST BODY_TYPE PLUMBING
J 2
(-5975 4250);
DISPLAY 0.872340 (-5975 4250);
PAINT GREEN (-5975 4250);
DISPLAY INVISIBLE (-5975 4250);
FORCEPROP 1 LAST HDL_TAP TRUE
J 2
(-6300 4075);
DISPLAY 0.872340 (-6300 4075);
DISPLAY INVISIBLE (-6300 4075);
FORCEPROP 1 LAST PATH I278
J 2
(-5973 4200);
DISPLAY 0.872340 (-5973 4200);
PAINT GREEN (-5973 4200);
DISPLAY INVISIBLE (-5973 4200);
FORCEADD TAP..1
R 2
(-5975 4100);
FORCEPROP 3 LASTPIN (-5925 4100) SIG_NAME M_H_CPU1_SB_DQS_DN<7>
J 0
(-5915 4110);
DISPLAY 0.659574 (-5915 4110);
PAINT MONO (-5915 4110);
DISPLAY INVISIBLE (-5915 4110);
FORCEPROP 1 LASTPIN (-5925 4100) BN 7
J 2
(-5913 4108);
DISPLAY 0.489362 (-5913 4108);
PAINT GREEN (-5913 4108);
FORCEPROP 2 LAST CDS_LIB mstr_standard
J 2
(-5975 4100);
DISPLAY 0.723404 (-5975 4100);
PAINT MONO (-5975 4100);
DISPLAY INVISIBLE (-5975 4100);
FORCEPROP 1 LAST BODY_TYPE PLUMBING
J 2
(-5975 4150);
DISPLAY 0.872340 (-5975 4150);
PAINT GREEN (-5975 4150);
DISPLAY INVISIBLE (-5975 4150);
FORCEPROP 1 LAST HDL_TAP TRUE
J 2
(-6300 3975);
DISPLAY 0.872340 (-6300 3975);
DISPLAY INVISIBLE (-6300 3975);
FORCEPROP 1 LAST PATH I279
J 2
(-5973 4100);
DISPLAY 0.872340 (-5973 4100);
PAINT GREEN (-5973 4100);
DISPLAY INVISIBLE (-5973 4100);
FORCEADD OFFPAGE..3
R 2
(-6675 5925);
FORCEPROP 2 LAST $XR0 105 
J 0
(-6955 5925);
DISPLAY 0.638298 (-6955 5925);
PAINT MONO (-6955 5925);
FORCEPROP 2 LAST CDS_LIB standard
J 0
(-6675 5925);
DISPLAY INVISIBLE (-6675 5925);
FORCEPROP 1 LAST OFFPAGE TRUE
J 2
(-7000 5800);
DISPLAY 0.872340 (-7000 5800);
PAINT GREEN (-7000 5800);
DISPLAY INVISIBLE (-7000 5800);
FORCEPROP 1 LAST COMMENT_BODY TRUE
J 2
(-6625 5825);
DISPLAY 0.872340 (-6625 5825);
PAINT GREEN (-6625 5825);
DISPLAY INVISIBLE (-6625 5825);
FORCEPROP 2 LAST PATH I280
J 0
(-6975 5975);
DISPLAY 1.021277 (-6975 5975);
DISPLAY INVISIBLE (-6975 5975);
FORCEADD OFFPAGE..3
R 2
(-6675 5875);
FORCEPROP 2 LAST $XR0 105 
J 0
(-6955 5875);
DISPLAY 0.638298 (-6955 5875);
PAINT MONO (-6955 5875);
FORCEPROP 2 LAST CDS_LIB standard
J 0
(-6675 5875);
DISPLAY INVISIBLE (-6675 5875);
FORCEPROP 1 LAST OFFPAGE TRUE
J 2
(-7000 5750);
DISPLAY 0.872340 (-7000 5750);
PAINT GREEN (-7000 5750);
DISPLAY INVISIBLE (-7000 5750);
FORCEPROP 1 LAST COMMENT_BODY TRUE
J 2
(-6625 5775);
DISPLAY 0.872340 (-6625 5775);
PAINT GREEN (-6625 5775);
DISPLAY INVISIBLE (-6625 5775);
FORCEPROP 2 LAST PATH I281
J 0
(-6975 5925);
DISPLAY 1.021277 (-6975 5925);
DISPLAY INVISIBLE (-6975 5925);
FORCEADD OFFPAGE..3
R 2
(-6675 4875);
FORCEPROP 2 LAST $XR0 105 
J 0
(-6955 4875);
DISPLAY 0.638298 (-6955 4875);
PAINT MONO (-6955 4875);
FORCEPROP 2 LAST CDS_LIB standard
J 0
(-6675 4875);
DISPLAY INVISIBLE (-6675 4875);
FORCEPROP 1 LAST OFFPAGE TRUE
J 2
(-7000 4750);
DISPLAY 0.872340 (-7000 4750);
PAINT GREEN (-7000 4750);
DISPLAY INVISIBLE (-7000 4750);
FORCEPROP 1 LAST COMMENT_BODY TRUE
J 2
(-6625 4775);
DISPLAY 0.872340 (-6625 4775);
PAINT GREEN (-6625 4775);
DISPLAY INVISIBLE (-6625 4775);
FORCEPROP 2 LAST PATH I282
J 0
(-6975 4925);
DISPLAY 1.021277 (-6975 4925);
DISPLAY INVISIBLE (-6975 4925);
FORCEADD OFFPAGE..3
R 2
(-6675 4825);
FORCEPROP 2 LAST $XR0 105 
J 0
(-6955 4825);
DISPLAY 0.638298 (-6955 4825);
PAINT MONO (-6955 4825);
FORCEPROP 2 LAST CDS_LIB standard
J 0
(-6675 4825);
DISPLAY INVISIBLE (-6675 4825);
FORCEPROP 1 LAST OFFPAGE TRUE
J 2
(-7000 4700);
DISPLAY 0.872340 (-7000 4700);
PAINT GREEN (-7000 4700);
DISPLAY INVISIBLE (-7000 4700);
FORCEPROP 1 LAST COMMENT_BODY TRUE
J 2
(-6625 4725);
DISPLAY 0.872340 (-6625 4725);
PAINT GREEN (-6625 4725);
DISPLAY INVISIBLE (-6625 4725);
FORCEPROP 2 LAST PATH I283
J 0
(-6975 4875);
DISPLAY 1.021277 (-6975 4875);
DISPLAY INVISIBLE (-6975 4875);
FORCEADD TAP..1
R 2
(-5775 4050);
FORCEPROP 3 LASTPIN (-5725 4050) SIG_NAME M_H_CPU1_SB_DQS_DP<8>
J 0
(-5715 4060);
DISPLAY 0.659574 (-5715 4060);
PAINT MONO (-5715 4060);
DISPLAY INVISIBLE (-5715 4060);
FORCEPROP 1 LASTPIN (-5725 4050) BN 8
J 2
(-5713 4058);
DISPLAY 0.489362 (-5713 4058);
PAINT GREEN (-5713 4058);
FORCEPROP 2 LAST CDS_LIB mstr_standard
J 2
(-5775 4050);
DISPLAY 0.723404 (-5775 4050);
PAINT MONO (-5775 4050);
DISPLAY INVISIBLE (-5775 4050);
FORCEPROP 1 LAST BODY_TYPE PLUMBING
J 2
(-5775 4100);
DISPLAY 0.872340 (-5775 4100);
PAINT GREEN (-5775 4100);
DISPLAY INVISIBLE (-5775 4100);
FORCEPROP 1 LAST HDL_TAP TRUE
J 2
(-6100 3925);
DISPLAY 0.872340 (-6100 3925);
DISPLAY INVISIBLE (-6100 3925);
FORCEPROP 1 LAST PATH I284
J 2
(-5773 4050);
DISPLAY 0.872340 (-5773 4050);
PAINT GREEN (-5773 4050);
DISPLAY INVISIBLE (-5773 4050);
FORCEADD TAP..1
R 2
(-5775 3950);
FORCEPROP 3 LASTPIN (-5725 3950) SIG_NAME M_H_CPU1_SB_DQS_DP<9>
J 0
(-5715 3960);
DISPLAY 0.659574 (-5715 3960);
PAINT MONO (-5715 3960);
DISPLAY INVISIBLE (-5715 3960);
FORCEPROP 1 LASTPIN (-5725 3950) BN 9
J 2
(-5713 3958);
DISPLAY 0.489362 (-5713 3958);
PAINT GREEN (-5713 3958);
FORCEPROP 2 LAST CDS_LIB mstr_standard
J 2
(-5775 3950);
DISPLAY 0.723404 (-5775 3950);
PAINT MONO (-5775 3950);
DISPLAY INVISIBLE (-5775 3950);
FORCEPROP 1 LAST BODY_TYPE PLUMBING
J 2
(-5775 4000);
DISPLAY 0.872340 (-5775 4000);
PAINT GREEN (-5775 4000);
DISPLAY INVISIBLE (-5775 4000);
FORCEPROP 1 LAST HDL_TAP TRUE
J 2
(-6100 3825);
DISPLAY 0.872340 (-6100 3825);
DISPLAY INVISIBLE (-6100 3825);
FORCEPROP 1 LAST PATH I285
J 2
(-5773 3950);
DISPLAY 0.872340 (-5773 3950);
PAINT GREEN (-5773 3950);
DISPLAY INVISIBLE (-5773 3950);
FORCEADD TAP..1
R 2
(-5975 4000);
FORCEPROP 3 LASTPIN (-5925 4000) SIG_NAME M_H_CPU1_SB_DQS_DN<8>
J 0
(-5915 4010);
DISPLAY 0.659574 (-5915 4010);
PAINT MONO (-5915 4010);
DISPLAY INVISIBLE (-5915 4010);
FORCEPROP 1 LASTPIN (-5925 4000) BN 8
J 2
(-5913 4008);
DISPLAY 0.489362 (-5913 4008);
PAINT GREEN (-5913 4008);
FORCEPROP 2 LAST CDS_LIB mstr_standard
J 2
(-5975 4000);
DISPLAY 0.723404 (-5975 4000);
PAINT MONO (-5975 4000);
DISPLAY INVISIBLE (-5975 4000);
FORCEPROP 1 LAST BODY_TYPE PLUMBING
J 2
(-5975 4050);
DISPLAY 0.872340 (-5975 4050);
PAINT GREEN (-5975 4050);
DISPLAY INVISIBLE (-5975 4050);
FORCEPROP 1 LAST HDL_TAP TRUE
J 2
(-6300 3875);
DISPLAY 0.872340 (-6300 3875);
DISPLAY INVISIBLE (-6300 3875);
FORCEPROP 1 LAST PATH I286
J 2
(-5973 4000);
DISPLAY 0.872340 (-5973 4000);
PAINT GREEN (-5973 4000);
DISPLAY INVISIBLE (-5973 4000);
FORCEADD TAP..1
R 2
(-5975 3900);
FORCEPROP 3 LASTPIN (-5925 3900) SIG_NAME M_H_CPU1_SB_DQS_DN<9>
J 0
(-5915 3910);
DISPLAY 0.659574 (-5915 3910);
PAINT MONO (-5915 3910);
DISPLAY INVISIBLE (-5915 3910);
FORCEPROP 1 LASTPIN (-5925 3900) BN 9
J 2
(-5913 3908);
DISPLAY 0.489362 (-5913 3908);
PAINT GREEN (-5913 3908);
FORCEPROP 2 LAST CDS_LIB mstr_standard
J 2
(-5975 3900);
DISPLAY 0.723404 (-5975 3900);
PAINT MONO (-5975 3900);
DISPLAY INVISIBLE (-5975 3900);
FORCEPROP 1 LAST BODY_TYPE PLUMBING
J 2
(-5975 3950);
DISPLAY 0.872340 (-5975 3950);
PAINT GREEN (-5975 3950);
DISPLAY INVISIBLE (-5975 3950);
FORCEPROP 1 LAST HDL_TAP TRUE
J 2
(-6300 3775);
DISPLAY 0.872340 (-6300 3775);
DISPLAY INVISIBLE (-6300 3775);
FORCEPROP 1 LAST PATH I287
J 2
(-5973 3900);
DISPLAY 0.872340 (-5973 3900);
PAINT GREEN (-5973 3900);
DISPLAY INVISIBLE (-5973 3900);
FORCEADD TAP..1
R 2
(-5975 3750);
FORCEPROP 3 LASTPIN (-5925 3750) SIG_NAME M_H_CPU1_SA_CA<0>
J 0
(-5915 3760);
DISPLAY 0.659574 (-5915 3760);
PAINT MONO (-5915 3760);
DISPLAY INVISIBLE (-5915 3760);
FORCEPROP 1 LASTPIN (-5925 3750) BN 0
J 2
(-5913 3758);
DISPLAY 0.489362 (-5913 3758);
PAINT GREEN (-5913 3758);
FORCEPROP 2 LAST CDS_LIB mstr_standard
J 0
(-5975 3750);
DISPLAY 0.723404 (-5975 3750);
PAINT MONO (-5975 3750);
DISPLAY INVISIBLE (-5975 3750);
FORCEPROP 1 LAST BODY_TYPE PLUMBING
J 2
(-5975 3800);
DISPLAY 0.872340 (-5975 3800);
PAINT GREEN (-5975 3800);
DISPLAY INVISIBLE (-5975 3800);
FORCEPROP 1 LAST HDL_TAP TRUE
J 2
(-6300 3625);
DISPLAY 0.872340 (-6300 3625);
DISPLAY INVISIBLE (-6300 3625);
FORCEPROP 1 LAST PATH I288
J 2
(-5973 3750);
DISPLAY 0.872340 (-5973 3750);
PAINT GREEN (-5973 3750);
DISPLAY INVISIBLE (-5973 3750);
FORCEADD TAP..1
R 2
(-5975 3700);
FORCEPROP 3 LASTPIN (-5925 3700) SIG_NAME M_H_CPU1_SA_CA<1>
J 0
(-5915 3710);
DISPLAY 0.659574 (-5915 3710);
PAINT MONO (-5915 3710);
DISPLAY INVISIBLE (-5915 3710);
FORCEPROP 1 LASTPIN (-5925 3700) BN 1
J 2
(-5913 3708);
DISPLAY 0.489362 (-5913 3708);
PAINT GREEN (-5913 3708);
FORCEPROP 2 LAST CDS_LIB mstr_standard
J 0
(-5975 3700);
DISPLAY 0.723404 (-5975 3700);
PAINT MONO (-5975 3700);
DISPLAY INVISIBLE (-5975 3700);
FORCEPROP 1 LAST BODY_TYPE PLUMBING
J 2
(-5975 3750);
DISPLAY 0.872340 (-5975 3750);
PAINT GREEN (-5975 3750);
DISPLAY INVISIBLE (-5975 3750);
FORCEPROP 1 LAST HDL_TAP TRUE
J 2
(-6300 3575);
DISPLAY 0.872340 (-6300 3575);
DISPLAY INVISIBLE (-6300 3575);
FORCEPROP 1 LAST PATH I289
J 2
(-5973 3700);
DISPLAY 0.872340 (-5973 3700);
PAINT GREEN (-5973 3700);
DISPLAY INVISIBLE (-5973 3700);
FORCEADD TAP..1
R 2
(-5975 3650);
FORCEPROP 3 LASTPIN (-5925 3650) SIG_NAME M_H_CPU1_SA_CA<2>
J 0
(-5915 3660);
DISPLAY 0.659574 (-5915 3660);
PAINT MONO (-5915 3660);
DISPLAY INVISIBLE (-5915 3660);
FORCEPROP 1 LASTPIN (-5925 3650) BN 2
J 2
(-5913 3658);
DISPLAY 0.489362 (-5913 3658);
PAINT GREEN (-5913 3658);
FORCEPROP 2 LAST CDS_LIB mstr_standard
J 0
(-5975 3650);
DISPLAY 0.723404 (-5975 3650);
PAINT MONO (-5975 3650);
DISPLAY INVISIBLE (-5975 3650);
FORCEPROP 1 LAST BODY_TYPE PLUMBING
J 2
(-5975 3700);
DISPLAY 0.872340 (-5975 3700);
PAINT GREEN (-5975 3700);
DISPLAY INVISIBLE (-5975 3700);
FORCEPROP 1 LAST HDL_TAP TRUE
J 2
(-6300 3525);
DISPLAY 0.872340 (-6300 3525);
DISPLAY INVISIBLE (-6300 3525);
FORCEPROP 1 LAST PATH I290
J 2
(-5973 3650);
DISPLAY 0.872340 (-5973 3650);
PAINT GREEN (-5973 3650);
DISPLAY INVISIBLE (-5973 3650);
FORCEADD TAP..1
R 2
(-5975 3600);
FORCEPROP 3 LASTPIN (-5925 3600) SIG_NAME M_H_CPU1_SA_CA<3>
J 0
(-5915 3610);
DISPLAY 0.659574 (-5915 3610);
PAINT MONO (-5915 3610);
DISPLAY INVISIBLE (-5915 3610);
FORCEPROP 1 LASTPIN (-5925 3600) BN 3
J 2
(-5913 3608);
DISPLAY 0.489362 (-5913 3608);
PAINT GREEN (-5913 3608);
FORCEPROP 2 LAST CDS_LIB mstr_standard
J 0
(-5975 3600);
DISPLAY 0.723404 (-5975 3600);
PAINT MONO (-5975 3600);
DISPLAY INVISIBLE (-5975 3600);
FORCEPROP 1 LAST BODY_TYPE PLUMBING
J 2
(-5975 3650);
DISPLAY 0.872340 (-5975 3650);
PAINT GREEN (-5975 3650);
DISPLAY INVISIBLE (-5975 3650);
FORCEPROP 1 LAST HDL_TAP TRUE
J 2
(-6300 3475);
DISPLAY 0.872340 (-6300 3475);
DISPLAY INVISIBLE (-6300 3475);
FORCEPROP 1 LAST PATH I291
J 2
(-5973 3600);
DISPLAY 0.872340 (-5973 3600);
PAINT GREEN (-5973 3600);
DISPLAY INVISIBLE (-5973 3600);
FORCEADD TAP..1
R 2
(-5975 3500);
FORCEPROP 3 LASTPIN (-5925 3500) SIG_NAME M_H_CPU1_SA_CA<5>
J 0
(-5915 3510);
DISPLAY 0.659574 (-5915 3510);
PAINT MONO (-5915 3510);
DISPLAY INVISIBLE (-5915 3510);
FORCEPROP 1 LASTPIN (-5925 3500) BN 5
J 2
(-5913 3508);
DISPLAY 0.489362 (-5913 3508);
PAINT GREEN (-5913 3508);
FORCEPROP 2 LAST CDS_LIB mstr_standard
J 0
(-5975 3500);
DISPLAY 0.723404 (-5975 3500);
PAINT MONO (-5975 3500);
DISPLAY INVISIBLE (-5975 3500);
FORCEPROP 1 LAST BODY_TYPE PLUMBING
J 2
(-5975 3550);
DISPLAY 0.872340 (-5975 3550);
PAINT GREEN (-5975 3550);
DISPLAY INVISIBLE (-5975 3550);
FORCEPROP 1 LAST HDL_TAP TRUE
J 2
(-6300 3375);
DISPLAY 0.872340 (-6300 3375);
DISPLAY INVISIBLE (-6300 3375);
FORCEPROP 1 LAST PATH I292
J 2
(-5973 3500);
DISPLAY 0.872340 (-5973 3500);
PAINT GREEN (-5973 3500);
DISPLAY INVISIBLE (-5973 3500);
FORCEADD TAP..1
R 2
(-5975 3550);
FORCEPROP 3 LASTPIN (-5925 3550) SIG_NAME M_H_CPU1_SA_CA<4>
J 0
(-5915 3560);
DISPLAY 0.659574 (-5915 3560);
PAINT MONO (-5915 3560);
DISPLAY INVISIBLE (-5915 3560);
FORCEPROP 1 LASTPIN (-5925 3550) BN 4
J 2
(-5913 3558);
DISPLAY 0.489362 (-5913 3558);
PAINT GREEN (-5913 3558);
FORCEPROP 2 LAST CDS_LIB mstr_standard
J 0
(-5975 3550);
DISPLAY 0.723404 (-5975 3550);
PAINT MONO (-5975 3550);
DISPLAY INVISIBLE (-5975 3550);
FORCEPROP 1 LAST BODY_TYPE PLUMBING
J 2
(-5975 3600);
DISPLAY 0.872340 (-5975 3600);
PAINT GREEN (-5975 3600);
DISPLAY INVISIBLE (-5975 3600);
FORCEPROP 1 LAST HDL_TAP TRUE
J 2
(-6300 3425);
DISPLAY 0.872340 (-6300 3425);
DISPLAY INVISIBLE (-6300 3425);
FORCEPROP 1 LAST PATH I293
J 2
(-5973 3550);
DISPLAY 0.872340 (-5973 3550);
PAINT GREEN (-5973 3550);
DISPLAY INVISIBLE (-5973 3550);
FORCEADD TAP..1
R 2
(-5975 3450);
FORCEPROP 3 LASTPIN (-5925 3450) SIG_NAME M_H_CPU1_SA_CA<6>
J 0
(-5915 3460);
DISPLAY 0.659574 (-5915 3460);
PAINT MONO (-5915 3460);
DISPLAY INVISIBLE (-5915 3460);
FORCEPROP 1 LASTPIN (-5925 3450) BN 6
J 2
(-5913 3458);
DISPLAY 0.489362 (-5913 3458);
PAINT GREEN (-5913 3458);
FORCEPROP 2 LAST CDS_LIB mstr_standard
J 0
(-5975 3450);
DISPLAY 0.723404 (-5975 3450);
PAINT MONO (-5975 3450);
DISPLAY INVISIBLE (-5975 3450);
FORCEPROP 1 LAST BODY_TYPE PLUMBING
J 2
(-5975 3500);
DISPLAY 0.872340 (-5975 3500);
PAINT GREEN (-5975 3500);
DISPLAY INVISIBLE (-5975 3500);
FORCEPROP 1 LAST HDL_TAP TRUE
J 2
(-6300 3325);
DISPLAY 0.872340 (-6300 3325);
DISPLAY INVISIBLE (-6300 3325);
FORCEPROP 1 LAST PATH I294
J 2
(-5973 3450);
DISPLAY 0.872340 (-5973 3450);
PAINT GREEN (-5973 3450);
DISPLAY INVISIBLE (-5973 3450);
FORCEADD TAP..1
R 2
(-5975 3350);
FORCEPROP 3 LASTPIN (-5925 3350) SIG_NAME M_H_CPU1_SB_CA<0>
J 0
(-5915 3360);
DISPLAY 0.659574 (-5915 3360);
PAINT MONO (-5915 3360);
DISPLAY INVISIBLE (-5915 3360);
FORCEPROP 1 LASTPIN (-5925 3350) BN 0
J 2
(-5913 3358);
DISPLAY 0.489362 (-5913 3358);
PAINT GREEN (-5913 3358);
FORCEPROP 2 LAST CDS_LIB mstr_standard
J 0
(-5975 3350);
DISPLAY 0.723404 (-5975 3350);
PAINT MONO (-5975 3350);
DISPLAY INVISIBLE (-5975 3350);
FORCEPROP 1 LAST BODY_TYPE PLUMBING
J 2
(-5975 3400);
DISPLAY 0.872340 (-5975 3400);
PAINT GREEN (-5975 3400);
DISPLAY INVISIBLE (-5975 3400);
FORCEPROP 1 LAST HDL_TAP TRUE
J 2
(-6300 3225);
DISPLAY 0.872340 (-6300 3225);
DISPLAY INVISIBLE (-6300 3225);
FORCEPROP 1 LAST PATH I295
J 2
(-5973 3350);
DISPLAY 0.872340 (-5973 3350);
PAINT GREEN (-5973 3350);
DISPLAY INVISIBLE (-5973 3350);
FORCEADD TAP..1
R 2
(-5975 3250);
FORCEPROP 3 LASTPIN (-5925 3250) SIG_NAME M_H_CPU1_SB_CA<2>
J 0
(-5915 3260);
DISPLAY 0.659574 (-5915 3260);
PAINT MONO (-5915 3260);
DISPLAY INVISIBLE (-5915 3260);
FORCEPROP 1 LASTPIN (-5925 3250) BN 2
J 2
(-5913 3258);
DISPLAY 0.489362 (-5913 3258);
PAINT GREEN (-5913 3258);
FORCEPROP 2 LAST CDS_LIB mstr_standard
J 0
(-5975 3250);
DISPLAY 0.723404 (-5975 3250);
PAINT MONO (-5975 3250);
DISPLAY INVISIBLE (-5975 3250);
FORCEPROP 1 LAST BODY_TYPE PLUMBING
J 2
(-5975 3300);
DISPLAY 0.872340 (-5975 3300);
PAINT GREEN (-5975 3300);
DISPLAY INVISIBLE (-5975 3300);
FORCEPROP 1 LAST HDL_TAP TRUE
J 2
(-6300 3125);
DISPLAY 0.872340 (-6300 3125);
DISPLAY INVISIBLE (-6300 3125);
FORCEPROP 1 LAST PATH I296
J 2
(-5973 3250);
DISPLAY 0.872340 (-5973 3250);
PAINT GREEN (-5973 3250);
DISPLAY INVISIBLE (-5973 3250);
FORCEADD TAP..1
R 2
(-5975 3300);
FORCEPROP 3 LASTPIN (-5925 3300) SIG_NAME M_H_CPU1_SB_CA<1>
J 0
(-5915 3310);
DISPLAY 0.659574 (-5915 3310);
PAINT MONO (-5915 3310);
DISPLAY INVISIBLE (-5915 3310);
FORCEPROP 1 LASTPIN (-5925 3300) BN 1
J 2
(-5913 3308);
DISPLAY 0.489362 (-5913 3308);
PAINT GREEN (-5913 3308);
FORCEPROP 2 LAST CDS_LIB mstr_standard
J 0
(-5975 3300);
DISPLAY 0.723404 (-5975 3300);
PAINT MONO (-5975 3300);
DISPLAY INVISIBLE (-5975 3300);
FORCEPROP 1 LAST BODY_TYPE PLUMBING
J 2
(-5975 3350);
DISPLAY 0.872340 (-5975 3350);
PAINT GREEN (-5975 3350);
DISPLAY INVISIBLE (-5975 3350);
FORCEPROP 1 LAST HDL_TAP TRUE
J 2
(-6300 3175);
DISPLAY 0.872340 (-6300 3175);
DISPLAY INVISIBLE (-6300 3175);
FORCEPROP 1 LAST PATH I297
J 2
(-5973 3300);
DISPLAY 0.872340 (-5973 3300);
PAINT GREEN (-5973 3300);
DISPLAY INVISIBLE (-5973 3300);
FORCEADD TAP..1
R 2
(-5975 3200);
FORCEPROP 3 LASTPIN (-5925 3200) SIG_NAME M_H_CPU1_SB_CA<3>
J 0
(-5915 3210);
DISPLAY 0.659574 (-5915 3210);
PAINT MONO (-5915 3210);
DISPLAY INVISIBLE (-5915 3210);
FORCEPROP 1 LASTPIN (-5925 3200) BN 3
J 2
(-5913 3208);
DISPLAY 0.489362 (-5913 3208);
PAINT GREEN (-5913 3208);
FORCEPROP 2 LAST CDS_LIB mstr_standard
J 0
(-5975 3200);
DISPLAY 0.723404 (-5975 3200);
PAINT MONO (-5975 3200);
DISPLAY INVISIBLE (-5975 3200);
FORCEPROP 1 LAST BODY_TYPE PLUMBING
J 2
(-5975 3250);
DISPLAY 0.872340 (-5975 3250);
PAINT GREEN (-5975 3250);
DISPLAY INVISIBLE (-5975 3250);
FORCEPROP 1 LAST HDL_TAP TRUE
J 2
(-6300 3075);
DISPLAY 0.872340 (-6300 3075);
DISPLAY INVISIBLE (-6300 3075);
FORCEPROP 1 LAST PATH I298
J 2
(-5973 3200);
DISPLAY 0.872340 (-5973 3200);
PAINT GREEN (-5973 3200);
DISPLAY INVISIBLE (-5973 3200);
FORCEADD TAP..1
R 2
(-5975 3100);
FORCEPROP 3 LASTPIN (-5925 3100) SIG_NAME M_H_CPU1_SB_CA<5>
J 0
(-5915 3110);
DISPLAY 0.659574 (-5915 3110);
PAINT MONO (-5915 3110);
DISPLAY INVISIBLE (-5915 3110);
FORCEPROP 1 LASTPIN (-5925 3100) BN 5
J 2
(-5913 3108);
DISPLAY 0.489362 (-5913 3108);
PAINT GREEN (-5913 3108);
FORCEPROP 2 LAST CDS_LIB mstr_standard
J 0
(-5975 3100);
DISPLAY 0.723404 (-5975 3100);
PAINT MONO (-5975 3100);
DISPLAY INVISIBLE (-5975 3100);
FORCEPROP 1 LAST BODY_TYPE PLUMBING
J 2
(-5975 3150);
DISPLAY 0.872340 (-5975 3150);
PAINT GREEN (-5975 3150);
DISPLAY INVISIBLE (-5975 3150);
FORCEPROP 1 LAST HDL_TAP TRUE
J 2
(-6300 2975);
DISPLAY 0.872340 (-6300 2975);
DISPLAY INVISIBLE (-6300 2975);
FORCEPROP 1 LAST PATH I299
J 2
(-5973 3100);
DISPLAY 0.872340 (-5973 3100);
PAINT GREEN (-5973 3100);
DISPLAY INVISIBLE (-5973 3100);
FORCEADD TAP..1
R 2
(-5975 3150);
FORCEPROP 3 LASTPIN (-5925 3150) SIG_NAME M_H_CPU1_SB_CA<4>
J 0
(-5915 3160);
DISPLAY 0.659574 (-5915 3160);
PAINT MONO (-5915 3160);
DISPLAY INVISIBLE (-5915 3160);
FORCEPROP 1 LASTPIN (-5925 3150) BN 4
J 2
(-5913 3158);
DISPLAY 0.489362 (-5913 3158);
PAINT GREEN (-5913 3158);
FORCEPROP 2 LAST CDS_LIB mstr_standard
J 0
(-5975 3150);
DISPLAY 0.723404 (-5975 3150);
PAINT MONO (-5975 3150);
DISPLAY INVISIBLE (-5975 3150);
FORCEPROP 1 LAST BODY_TYPE PLUMBING
J 2
(-5975 3200);
DISPLAY 0.872340 (-5975 3200);
PAINT GREEN (-5975 3200);
DISPLAY INVISIBLE (-5975 3200);
FORCEPROP 1 LAST HDL_TAP TRUE
J 2
(-6300 3025);
DISPLAY 0.872340 (-6300 3025);
DISPLAY INVISIBLE (-6300 3025);
FORCEPROP 1 LAST PATH I300
J 2
(-5973 3150);
DISPLAY 0.872340 (-5973 3150);
PAINT GREEN (-5973 3150);
DISPLAY INVISIBLE (-5973 3150);
FORCEADD TAP..1
R 2
(-5975 3050);
FORCEPROP 3 LASTPIN (-5925 3050) SIG_NAME M_H_CPU1_SB_CA<6>
J 0
(-5915 3060);
DISPLAY 0.659574 (-5915 3060);
PAINT MONO (-5915 3060);
DISPLAY INVISIBLE (-5915 3060);
FORCEPROP 1 LASTPIN (-5925 3050) BN 6
J 2
(-5913 3058);
DISPLAY 0.489362 (-5913 3058);
PAINT GREEN (-5913 3058);
FORCEPROP 2 LAST CDS_LIB mstr_standard
J 0
(-5975 3050);
DISPLAY 0.723404 (-5975 3050);
PAINT MONO (-5975 3050);
DISPLAY INVISIBLE (-5975 3050);
FORCEPROP 1 LAST BODY_TYPE PLUMBING
J 2
(-5975 3100);
DISPLAY 0.872340 (-5975 3100);
PAINT GREEN (-5975 3100);
DISPLAY INVISIBLE (-5975 3100);
FORCEPROP 1 LAST HDL_TAP TRUE
J 2
(-6300 2925);
DISPLAY 0.872340 (-6300 2925);
DISPLAY INVISIBLE (-6300 2925);
FORCEPROP 1 LAST PATH I301
J 2
(-5973 3050);
DISPLAY 0.872340 (-5973 3050);
PAINT GREEN (-5973 3050);
DISPLAY INVISIBLE (-5973 3050);
FORCEADD OFFPAGE..2
R 2
(-6575 3775);
FORCEPROP 2 LAST $XR0 105 
J 0
(-6830 3775);
DISPLAY 0.638298 (-6830 3775);
PAINT MONO (-6830 3775);
FORCEPROP 2 LAST CDS_LIB standard
J 0
(-6575 3775);
DISPLAY INVISIBLE (-6575 3775);
FORCEPROP 1 LAST OFFPAGE TRUE
J 2
(-6900 3650);
DISPLAY 0.872340 (-6900 3650);
PAINT GREEN (-6900 3650);
DISPLAY INVISIBLE (-6900 3650);
FORCEPROP 1 LAST COMMENT_BODY TRUE
J 2
(-6530 3680);
DISPLAY 0.872340 (-6530 3680);
PAINT GREEN (-6530 3680);
DISPLAY INVISIBLE (-6530 3680);
FORCEPROP 2 LAST PATH I302
J 0
(-6825 3825);
DISPLAY 1.021277 (-6825 3825);
DISPLAY INVISIBLE (-6825 3825);
FORCEADD OFFPAGE..2
R 2
(-6575 3375);
FORCEPROP 2 LAST $XR0 105 
J 0
(-6830 3375);
DISPLAY 0.638298 (-6830 3375);
PAINT MONO (-6830 3375);
FORCEPROP 2 LAST CDS_LIB standard
J 0
(-6575 3375);
DISPLAY INVISIBLE (-6575 3375);
FORCEPROP 1 LAST OFFPAGE TRUE
J 2
(-6900 3250);
DISPLAY 0.872340 (-6900 3250);
PAINT GREEN (-6900 3250);
DISPLAY INVISIBLE (-6900 3250);
FORCEPROP 1 LAST COMMENT_BODY TRUE
J 2
(-6530 3280);
DISPLAY 0.872340 (-6530 3280);
PAINT GREEN (-6530 3280);
DISPLAY INVISIBLE (-6530 3280);
FORCEPROP 2 LAST PATH I303
J 0
(-6825 3425);
DISPLAY 1.021277 (-6825 3425);
DISPLAY INVISIBLE (-6825 3425);
FORCEADD OFFPAGE..2
R 2
(-6575 2850);
FORCEPROP 2 LAST $XR0 105 
J 0
(-6830 2850);
DISPLAY 0.638298 (-6830 2850);
PAINT MONO (-6830 2850);
FORCEPROP 2 LAST CDS_LIB standard
J 0
(-6575 2850);
DISPLAY INVISIBLE (-6575 2850);
FORCEPROP 1 LAST OFFPAGE TRUE
J 2
(-6900 2725);
DISPLAY 0.872340 (-6900 2725);
PAINT GREEN (-6900 2725);
DISPLAY INVISIBLE (-6900 2725);
FORCEPROP 1 LAST COMMENT_BODY TRUE
J 2
(-6530 2755);
DISPLAY 0.872340 (-6530 2755);
PAINT GREEN (-6530 2755);
DISPLAY INVISIBLE (-6530 2755);
FORCEPROP 2 LAST PATH I304
J 0
(-6825 2900);
DISPLAY 1.021277 (-6825 2900);
DISPLAY INVISIBLE (-6825 2900);
FORCEADD OFFPAGE..2
R 2
(-6575 2900);
FORCEPROP 2 LAST $XR0 105 
J 0
(-6830 2900);
DISPLAY 0.638298 (-6830 2900);
PAINT MONO (-6830 2900);
FORCEPROP 2 LAST CDS_LIB standard
J 0
(-6575 2900);
DISPLAY INVISIBLE (-6575 2900);
FORCEPROP 1 LAST OFFPAGE TRUE
J 2
(-6900 2775);
DISPLAY 0.872340 (-6900 2775);
PAINT GREEN (-6900 2775);
DISPLAY INVISIBLE (-6900 2775);
FORCEPROP 1 LAST COMMENT_BODY TRUE
J 2
(-6530 2805);
DISPLAY 0.872340 (-6530 2805);
PAINT GREEN (-6530 2805);
DISPLAY INVISIBLE (-6530 2805);
FORCEPROP 2 LAST PATH I305
J 0
(-6825 2950);
DISPLAY 1.021277 (-6825 2950);
DISPLAY INVISIBLE (-6825 2950);
FORCEADD OFFPAGE..2
R 2
(-6575 2750);
FORCEPROP 2 LAST $XR0 105 
J 0
(-6830 2750);
DISPLAY 0.638298 (-6830 2750);
PAINT MONO (-6830 2750);
FORCEPROP 2 LAST CDS_LIB standard
J 0
(-6575 2750);
DISPLAY INVISIBLE (-6575 2750);
FORCEPROP 1 LAST OFFPAGE TRUE
J 2
(-6900 2625);
DISPLAY 0.872340 (-6900 2625);
PAINT GREEN (-6900 2625);
DISPLAY INVISIBLE (-6900 2625);
FORCEPROP 1 LAST COMMENT_BODY TRUE
J 2
(-6530 2655);
DISPLAY 0.872340 (-6530 2655);
PAINT GREEN (-6530 2655);
DISPLAY INVISIBLE (-6530 2655);
FORCEPROP 2 LAST PATH I306
J 0
(-6825 2800);
DISPLAY 1.021277 (-6825 2800);
DISPLAY INVISIBLE (-6825 2800);
FORCEADD OFFPAGE..2
R 2
(-6575 2700);
FORCEPROP 2 LAST $XR0 105 
J 0
(-6830 2700);
DISPLAY 0.638298 (-6830 2700);
PAINT MONO (-6830 2700);
FORCEPROP 2 LAST CDS_LIB standard
J 0
(-6575 2700);
DISPLAY INVISIBLE (-6575 2700);
FORCEPROP 1 LAST OFFPAGE TRUE
J 2
(-6900 2575);
DISPLAY 0.872340 (-6900 2575);
PAINT GREEN (-6900 2575);
DISPLAY INVISIBLE (-6900 2575);
FORCEPROP 1 LAST COMMENT_BODY TRUE
J 2
(-6530 2605);
DISPLAY 0.872340 (-6530 2605);
PAINT GREEN (-6530 2605);
DISPLAY INVISIBLE (-6530 2605);
FORCEPROP 2 LAST PATH I307
J 0
(-6825 2750);
DISPLAY 1.021277 (-6825 2750);
DISPLAY INVISIBLE (-6825 2750);
FORCEADD OFFPAGE..1
(-6575 2600);
FORCEPROP 2 LAST $XR0 105 
J 0
(-6857 2600);
DISPLAY 0.638298 (-6857 2600);
PAINT MONO (-6857 2600);
FORCEPROP 2 LAST CDS_LIB standard
J 0
(-6575 2600);
DISPLAY INVISIBLE (-6575 2600);
FORCEPROP 1 LAST OFFPAGE TRUE
J 0
(-6250 2475);
DISPLAY 0.872340 (-6250 2475);
PAINT GREEN (-6250 2475);
DISPLAY INVISIBLE (-6250 2475);
FORCEPROP 1 LAST COMMENT_BODY TRUE
J 0
(-6450 2500);
DISPLAY 0.872340 (-6450 2500);
PAINT GREEN (-6450 2500);
DISPLAY INVISIBLE (-6450 2500);
FORCEPROP 2 LAST PATH I308
J 0
(-6850 2650);
DISPLAY 1.021277 (-6850 2650);
DISPLAY INVISIBLE (-6850 2650);
FORCEADD OFFPAGE..5
(-6575 2500);
FORCEPROP 2 LAST $XR0 105 
J 0
(-6830 2500);
DISPLAY 0.638298 (-6830 2500);
PAINT MONO (-6830 2500);
FORCEPROP 2 LAST CDS_LIB mstr_standard
J 0
(-6575 2500);
DISPLAY INVISIBLE (-6575 2500);
FORCEPROP 1 LAST OFFPAGE TRUE
J 0
(-6250 2375);
DISPLAY 0.872340 (-6250 2375);
PAINT GREEN (-6250 2375);
DISPLAY INVISIBLE (-6250 2375);
FORCEPROP 1 LAST COMMENT_BODY TRUE
J 0
(-6475 2425);
DISPLAY 0.872340 (-6475 2425);
PAINT GREEN (-6475 2425);
DISPLAY INVISIBLE (-6475 2425);
FORCEPROP 2 LAST PATH I309
J 0
(-6825 2550);
DISPLAY 1.021277 (-6825 2550);
DISPLAY INVISIBLE (-6825 2550);
FORCEADD OFFPAGE..2
R 2
(-6575 2350);
FORCEPROP 2 LAST $XR0 105 
J 0
(-6830 2350);
DISPLAY 0.638298 (-6830 2350);
PAINT MONO (-6830 2350);
FORCEPROP 2 LAST CDS_LIB standard
J 0
(-6575 2350);
DISPLAY INVISIBLE (-6575 2350);
FORCEPROP 1 LAST OFFPAGE TRUE
J 2
(-6900 2225);
DISPLAY 0.872340 (-6900 2225);
PAINT GREEN (-6900 2225);
DISPLAY INVISIBLE (-6900 2225);
FORCEPROP 1 LAST COMMENT_BODY TRUE
J 2
(-6530 2255);
DISPLAY 0.872340 (-6530 2255);
PAINT GREEN (-6530 2255);
DISPLAY INVISIBLE (-6530 2255);
FORCEPROP 2 LAST PATH I310
J 0
(-6825 2400);
DISPLAY 1.021277 (-6825 2400);
DISPLAY INVISIBLE (-6825 2400);
FORCEADD OFFPAGE..2
R 2
(-6575 2400);
FORCEPROP 2 LAST $XR0 105 
J 0
(-6830 2400);
DISPLAY 0.638298 (-6830 2400);
PAINT MONO (-6830 2400);
FORCEPROP 2 LAST CDS_LIB standard
J 0
(-6575 2400);
DISPLAY INVISIBLE (-6575 2400);
FORCEPROP 1 LAST OFFPAGE TRUE
J 2
(-6900 2275);
DISPLAY 0.872340 (-6900 2275);
PAINT GREEN (-6900 2275);
DISPLAY INVISIBLE (-6900 2275);
FORCEPROP 1 LAST COMMENT_BODY TRUE
J 2
(-6530 2305);
DISPLAY 0.872340 (-6530 2305);
PAINT GREEN (-6530 2305);
DISPLAY INVISIBLE (-6530 2305);
FORCEPROP 2 LAST PATH I311
J 0
(-6825 2450);
DISPLAY 1.021277 (-6825 2450);
DISPLAY INVISIBLE (-6825 2450);
FORCEADD OFFPAGE..1
(-6575 2250);
FORCEPROP 2 LAST $XR0 105 
J 0
(-6857 2250);
DISPLAY 0.638298 (-6857 2250);
PAINT MONO (-6857 2250);
FORCEPROP 2 LAST CDS_LIB standard
J 0
(-6575 2250);
DISPLAY INVISIBLE (-6575 2250);
FORCEPROP 1 LAST OFFPAGE TRUE
J 0
(-6250 2125);
DISPLAY 0.872340 (-6250 2125);
PAINT GREEN (-6250 2125);
DISPLAY INVISIBLE (-6250 2125);
FORCEPROP 1 LAST COMMENT_BODY TRUE
J 0
(-6450 2150);
DISPLAY 0.872340 (-6450 2150);
PAINT GREEN (-6450 2150);
DISPLAY INVISIBLE (-6450 2150);
FORCEPROP 2 LAST PATH I312
J 0
(-6850 2300);
DISPLAY 1.021277 (-6850 2300);
DISPLAY INVISIBLE (-6850 2300);
FORCEADD OFFPAGE..5
(-6575 2150);
FORCEPROP 2 LAST $XR0 105 
J 0
(-6830 2150);
DISPLAY 0.638298 (-6830 2150);
PAINT MONO (-6830 2150);
FORCEPROP 2 LAST CDS_LIB standard
J 0
(-6575 2150);
DISPLAY INVISIBLE (-6575 2150);
FORCEPROP 1 LAST OFFPAGE TRUE
J 0
(-6250 2025);
DISPLAY 0.872340 (-6250 2025);
PAINT GREEN (-6250 2025);
DISPLAY INVISIBLE (-6250 2025);
FORCEPROP 1 LAST COMMENT_BODY TRUE
J 0
(-6475 2075);
DISPLAY 0.872340 (-6475 2075);
PAINT GREEN (-6475 2075);
DISPLAY INVISIBLE (-6475 2075);
FORCEPROP 2 LAST PATH I313
J 0
(-6825 2200);
DISPLAY 1.021277 (-6825 2200);
DISPLAY INVISIBLE (-6825 2200);
FORCEADD Q_RES..1
(-6650 2050);
FORCEPROP 1 LAST LOCATION R507
J 0
(-6975 2050);
DISPLAY 0.489362 (-6975 2050);
PAINT SKYBLUE (-6975 2050);
FORCEPROP 0 LAST $SEC 1
J 0
(-6825 2100);
DISPLAY 0.680851 (-6825 2100);
PAINT MONO (-6825 2100);
DISPLAY INVISIBLE (-6825 2100);
FORCEPROP 0 LAST CDS_SEC 1
J 0
(-6825 2100);
DISPLAY 1.021277 (-6825 2100);
DISPLAY INVISIBLE (-6825 2100);
FORCEPROP 1 LASTPIN (-6750 2050) $PN 1
J 0
(-6738 2062);
DISPLAY 0.489362 (-6738 2062);
PAINT MONO (-6738 2062);
FORCEPROP 1 LASTPIN (-6550 2050) $PN 2
J 0
(-6588 2062);
DISPLAY 0.489362 (-6588 2062);
PAINT MONO (-6588 2062);
FORCEPROP 1 LAST PACK_TYPE 0402LF
J 0
(-6975 2025);
DISPLAY 0.489362 (-6975 2025);
PAINT SKYBLUE (-6975 2025);
FORCEPROP 1 LAST TOLERANCE 1%
J 0
(-6375 2050);
DISPLAY 0.489362 (-6375 2050);
PAINT SKYBLUE (-6375 2050);
FORCEPROP 1 LAST VALUE 15
J 2
(-6325 2050);
DISPLAY 0.489362 (-6325 2050);
PAINT SKYBLUE (-6325 2050);
FORCEPROP 1 LAST MATERIAL CHIP
J 0
(-6775 2175);
DISPLAY 0.638298 (-6775 2175);
PAINT SKYBLUE (-6775 2175);
DISPLAY INVISIBLE (-6775 2175);
FORCEPROP 1 LAST WATTAGE 1/16W
J 2
(-6425 2175);
DISPLAY 0.638298 (-6425 2175);
PAINT SKYBLUE (-6425 2175);
DISPLAY INVISIBLE (-6425 2175);
FORCEPROP 2 LAST CDS_LIB pure_quanta
J 0
(-6650 2050);
DISPLAY INVISIBLE (-6650 2050);
FORCEPROP 1 LAST PATH I314
J 0
(-6700 2200);
DISPLAY 0.978723 (-6700 2200);
PAINT WHITE (-6700 2200);
DISPLAY INVISIBLE (-6700 2200);
FORCEPROP 1 LAST PART_NUMBER CS01502FB03
J 0
(-6525 2025);
DISPLAY 0.489362 (-6525 2025);
PAINT SKYBLUE (-6525 2025);
DISPLAY INVISIBLE (-6525 2025);
FORCEADD OFFPAGE..5
(-6575 1950);
FORCEPROP 2 LAST $XR0 105 
J 0
(-6830 1950);
DISPLAY 0.638298 (-6830 1950);
PAINT MONO (-6830 1950);
FORCEPROP 2 LAST CDS_LIB standard
J 0
(-6575 1950);
DISPLAY INVISIBLE (-6575 1950);
FORCEPROP 1 LAST OFFPAGE TRUE
J 0
(-6250 1825);
DISPLAY 0.872340 (-6250 1825);
PAINT GREEN (-6250 1825);
DISPLAY INVISIBLE (-6250 1825);
FORCEPROP 1 LAST COMMENT_BODY TRUE
J 0
(-6475 1875);
DISPLAY 0.872340 (-6475 1875);
PAINT GREEN (-6475 1875);
DISPLAY INVISIBLE (-6475 1875);
FORCEPROP 2 LAST PATH I315
J 0
(-6825 2000);
DISPLAY 1.021277 (-6825 2000);
DISPLAY INVISIBLE (-6825 2000);
FORCEADD OFFPAGE..1
(-7525 2050);
FORCEPROP 2 LAST $XR0 105 
J 0
(-7777 2050);
DISPLAY 0.638298 (-7777 2050);
PAINT MONO (-7777 2050);
FORCEPROP 2 LAST CDS_LIB mstr_standard
J 0
(-7525 2050);
DISPLAY INVISIBLE (-7525 2050);
FORCEPROP 1 LAST OFFPAGE TRUE
J 0
(-7200 1925);
DISPLAY 0.872340 (-7200 1925);
PAINT GREEN (-7200 1925);
DISPLAY INVISIBLE (-7200 1925);
FORCEPROP 1 LAST COMMENT_BODY TRUE
J 0
(-7400 1950);
DISPLAY 0.872340 (-7400 1950);
PAINT GREEN (-7400 1950);
DISPLAY INVISIBLE (-7400 1950);
FORCEPROP 2 LAST PATH I316
J 0
(-7775 2100);
DISPLAY 1.021277 (-7775 2100);
DISPLAY INVISIBLE (-7775 2100);
FORCEADD CAD_NOTE..1
(-7725 2325);
FORCEPROP 0 LAST L1 R1985 PLACE CLOSE TO CPU < 25MM
J 0
(-7875 2200);
DISPLAY 0.617021 (-7875 2200);
PAINT WHITE (-7875 2200);
FORCEPROP 2 LAST CDS_LIB pure_quanta_power
J 0
(-7725 2325);
DISPLAY INVISIBLE (-7725 2325);
FORCEPROP 1 LAST COMMENT_BODY TRUE
J 0
(-7700 2425);
DISPLAY 0.574468 (-7700 2425);
PAINT WHITE (-7700 2425);
DISPLAY INVISIBLE (-7700 2425);
FORCEADD QUANTA_TITLE_BLOCK_C..1
(0 0);
FORCEPROP 0 LAST CDS_CON_LAST_MODIFIED Thu Sep 14 16:11:57 2023
J 0
(-1885 15);
DISPLAY INVISIBLE (-1885 15);
FORCEPROP 1 LAST CUSTOM_TXT_CDS <CON_LAST_MODIFIED>
J 0
(-1885 15);
DISPLAY 0.978723 (-1885 15);
FORCEPROP 2 LAST CUSTOM_TXT_CDS <XR_PAGE_TITLE>
J 0
(-7890 5250);
DISPLAY 0.638298 (-7890 5250);
PAINT PINK (-7890 5250);
DISPLAY INVISIBLE (-7890 5250);
FORCEPROP 1 LAST CUSTOM_TXT_CDS <NAME_2>
J 0
(-3175 50);
FORCEPROP 1 LAST CUSTOM_TXT_CDS <NAME_1>
J 0
(-3175 175);
FORCEPROP 1 LAST CUSTOM_TXT_CDS <Q_NUMBER>
J 0
(-1403 103);
DISPLAY 1.212766 (-1403 103);
FORCEPROP 1 LAST CUSTOM_TXT_CDS <Q_PROJ>
J 0
(-2382 102);
DISPLAY 1.212766 (-2382 102);
FORCEPROP 1 LAST CUSTOM_TXT_CDS <Q_REV>
J 0
(-184 103);
DISPLAY 1.212766 (-184 103);
FORCEPROP 1 LAST CUSTOM_TXT_CDS <CON_PAGE_NUM> OF <CON_TOTAL_PAGES>
J 0
(-446 18);
DISPLAY 0.978723 (-446 18);
FORCEPROP 1 LAST Q_TITLE CPU1 DDR CHH
J 0
(-9366 26);
DISPLAY 2.446809 (-9366 26);
PAINT GREEN (-9366 26);
FORCEPROP 2 LAST PAGE_BORDER TRUE
J 0
(-7890 5250);
DISPLAY 0.638298 (-7890 5250);
PAINT PINK (-7890 5250);
DISPLAY INVISIBLE (-7890 5250);
FORCEPROP 2 LAST CDS_LIB pure_quanta
J 0
(0 0);
DISPLAY INVISIBLE (0 0);
FORCEPROP 1 LAST CDS_LMAN_SYM_OUTLINE -9475,6775,100,-125
J 0
(0 0);
DISPLAY 0.468085 (0 0);
PAINT GREEN (0 0);
DISPLAY INVISIBLE (0 0);
FORCEPROP 2 LAST CDS_XR_PAGE_TITLE CR-44 : @T6G_MB_LIB.T6G(SCH_1):PAGE44
J 0
(-7890 5250);
DISPLAY 0.638298 (-7890 5250);
PAINT PINK (-7890 5250);
DISPLAY INVISIBLE (-7890 5250);
FORCEPROP 1 LAST Q_DEPT BU9
J 1
(-3763 49);
DISPLAY 1.957447 (-3763 49);
PAINT GREEN (-3763 49);
DISPLAY INVISIBLE (-3763 49);
FORCEPROP 1 LAST COMMENT_BODY TRUE
J 0
(12 -13);
DISPLAY 0.978723 (12 -13);
PAINT GREEN (12 -13);
DISPLAY INVISIBLE (12 -13);
WIRE 17 -1 (-3300 5925)(-2675 5925);
FORCEPROP 2 LAST SIG_NAME M_H_CPU1_SA_DQ<31:0>
J 2
(-2735 5935);
DISPLAY 0.489362 (-2735 5935);
WIRE 17 -1 (-3300 5925)(-3300 5875);
WIRE 17 -1 (-3300 5875)(-3300 5825);
WIRE 17 -1 (-3300 5825)(-3300 5775);
WIRE 17 -1 (-3300 5775)(-3300 5725);
WIRE 17 -1 (-3300 5725)(-3300 5675);
WIRE 17 -1 (-3300 5675)(-3300 5625);
WIRE 17 -1 (-3300 5625)(-3300 5575);
WIRE 17 -1 (-3300 5575)(-3300 5475);
WIRE 17 -1 (-3300 5475)(-3300 5425);
WIRE 17 -1 (-3300 5425)(-3300 5375);
WIRE 17 -1 (-3300 5375)(-3300 5325);
WIRE 17 -1 (-3300 5325)(-3300 5275);
WIRE 17 -1 (-3300 5275)(-3300 5225);
WIRE 17 -1 (-3300 5225)(-3300 5175);
WIRE 17 -1 (-3300 5175)(-3300 5125);
WIRE 17 -1 (-3300 5025)(-3300 5125);
WIRE 17 -1 (-3300 4975)(-3300 5025);
WIRE 17 -1 (-3300 4925)(-3300 4975);
WIRE 17 -1 (-3300 4875)(-3300 4925);
WIRE 17 -1 (-3300 4875)(-3300 4825);
WIRE 17 -1 (-3300 4825)(-3300 4775);
WIRE 17 -1 (-3300 4775)(-3300 4725);
WIRE 17 -1 (-3300 4725)(-3300 4675);
WIRE 17 -1 (-3300 4675)(-3300 4575);
WIRE 17 -1 (-3300 4575)(-3300 4525);
WIRE 17 -1 (-3300 4525)(-3300 4475);
WIRE 17 -1 (-3300 4475)(-3300 4425);
WIRE 17 -1 (-3300 4375)(-3300 4425);
WIRE 17 -1 (-3300 4325)(-3300 4375);
WIRE 17 -1 (-3300 4275)(-3300 4325);
WIRE 17 -1 (-3300 4225)(-3300 4275);
WIRE 17 -1 (-3300 4125)(-2675 4125);
FORCEPROP 2 LAST SIG_NAME M_H_CPU1_SB_DQ<31:0>
J 2
(-2735 4135);
DISPLAY 0.489362 (-2735 4135);
WIRE 17 -1 (-3300 3625)(-3300 3575);
WIRE 17 -1 (-3300 3675)(-3300 3625);
WIRE 17 -1 (-3300 3575)(-3300 3525);
WIRE 17 -1 (-3300 3525)(-3300 3475);
WIRE 17 -1 (-3300 3775)(-3300 3675);
WIRE 17 -1 (-3300 3825)(-3300 3775);
WIRE 17 -1 (-3300 3475)(-3300 3425);
WIRE 17 -1 (-3300 3425)(-3300 3375);
WIRE 17 -1 (-3300 3875)(-3300 3825);
WIRE 17 -1 (-3300 3925)(-3300 3875);
WIRE 17 -1 (-3300 3375)(-3300 3325);
WIRE 17 -1 (-3300 3225)(-3300 3325);
WIRE 17 -1 (-3300 3975)(-3300 3925);
WIRE 17 -1 (-3300 4025)(-3300 3975);
WIRE 17 -1 (-3300 3175)(-3300 3225);
WIRE 17 -1 (-3300 3125)(-3300 3175);
WIRE 17 -1 (-3300 4075)(-3300 4025);
WIRE 17 -1 (-3300 4125)(-3300 4075);
WIRE 17 -1 (-3300 3075)(-3300 3125);
WIRE 17 -1 (-3300 3075)(-3300 3025);
WIRE 17 -1 (-3300 3025)(-3300 2975);
WIRE 17 -1 (-3300 2975)(-3300 2925);
WIRE 17 -1 (-3300 2925)(-3300 2875);
WIRE 17 -1 (-3300 2875)(-3300 2775);
WIRE 17 -1 (-3300 2775)(-3300 2725);
WIRE 17 -1 (-3300 2725)(-3300 2675);
WIRE 17 -1 (-3300 2675)(-3300 2625);
WIRE 17 -1 (-3300 2575)(-3300 2625);
WIRE 17 -1 (-3300 2525)(-3300 2575);
WIRE 17 -1 (-3300 2475)(-3300 2525);
WIRE 17 -1 (-3300 2425)(-3300 2475);
WIRE 17 -1 (-3300 2325)(-3300 2350);
WIRE 17 -1 (-3300 2325)(-3300 2275);
WIRE 17 -1 (-3300 2350)(-2800 2350);
FORCEPROP 2 LAST SIG_NAME M_H_CPU1_SA_CB<7:0>
J 2
(-2800 2360);
DISPLAY 0.489362 (-2800 2360);
WIRE 17 -1 (-3300 2225)(-3300 2275);
WIRE 17 -1 (-3300 2225)(-3300 2175);
WIRE 17 -1 (-3300 2125)(-3300 2175);
WIRE 17 -1 (-3300 2075)(-3300 2125);
WIRE 17 -1 (-3300 2025)(-3300 2075);
WIRE 17 -1 (-3300 1975)(-3300 2025);
WIRE 17 -1 (-3300 1875)(-3300 1900);
WIRE 17 -1 (-3300 1875)(-3300 1825);
WIRE 17 -1 (-3300 1900)(-2800 1900);
FORCEPROP 2 LAST SIG_NAME M_H_CPU1_SB_CB<7:0>
J 2
(-2800 1910);
DISPLAY 0.489362 (-2800 1910);
WIRE 17 -1 (-3300 1775)(-3300 1825);
WIRE 17 -1 (-3300 1775)(-3300 1725);
WIRE 17 -1 (-3300 1675)(-3300 1725);
WIRE 17 -1 (-3300 1625)(-3300 1675);
WIRE 17 -1 (-3300 1575)(-3300 1625);
WIRE 17 -1 (-3300 1525)(-3300 1575);
WIRE 17 -1 (-6025 5775)(-6025 5675);
WIRE 17 -1 (-6025 5875)(-6025 5775);
FORCEPROP 2 LAST SIG_NAME M_H_CPU1_SA_DQS_DN<9:0>
J 2
(-6060 5885);
DISPLAY 0.489362 (-6060 5885);
WIRE 17 -1 (-6025 5675)(-6025 5575);
WIRE 17 -1 (-6025 5575)(-6025 5475);
WIRE 17 -1 (-6025 5375)(-6025 5475);
WIRE 17 -1 (-6025 5275)(-6025 5375);
WIRE 17 -1 (-5825 5925)(-5825 5825);
WIRE 17 -1 (-5825 5925)(-6625 5925);
FORCEPROP 2 LAST SIG_NAME M_H_CPU1_SA_DQS_DP<9:0>
J 2
(-6060 5935);
DISPLAY 0.489362 (-6060 5935);
WIRE 17 -1 (-6025 5175)(-6025 5275);
WIRE 17 -1 (-6025 5175)(-6025 5075);
WIRE 17 -1 (-6025 5075)(-6025 4975);
WIRE 17 -1 (-5825 5825)(-5825 5725);
WIRE 17 -1 (-5825 5725)(-5825 5625);
WIRE 17 -1 (-5825 5625)(-5825 5525);
WIRE 17 -1 (-5825 5425)(-5825 5525);
WIRE 17 -1 (-5825 5325)(-5825 5425);
WIRE 17 -1 (-5825 5225)(-5825 5325);
WIRE 17 -1 (-5825 5225)(-5825 5125);
WIRE 17 -1 (-5825 5125)(-5825 5025);
WIRE 17 -1 (-6025 4825)(-6025 4725);
FORCEPROP 2 LAST SIG_NAME M_H_CPU1_SB_DQS_DN<9:0>
J 2
(-6060 4835);
DISPLAY 0.489362 (-6060 4835);
WIRE 17 -1 (-6025 4725)(-6025 4625);
WIRE 17 -1 (-6025 4625)(-6025 4525);
WIRE 17 -1 (-6025 4525)(-6025 4425);
WIRE 17 -1 (-6025 4325)(-6025 4425);
WIRE 17 -1 (-6025 4225)(-6025 4325);
WIRE 17 -1 (-5825 4875)(-5825 4775);
WIRE 17 -1 (-5825 4875)(-6625 4875);
FORCEPROP 2 LAST SIG_NAME M_H_CPU1_SB_DQS_DP<9:0>
J 2
(-6060 4885);
DISPLAY 0.489362 (-6060 4885);
WIRE 17 -1 (-6025 4125)(-6025 4225);
WIRE 17 -1 (-6025 4125)(-6025 4025);
WIRE 17 -1 (-6025 4025)(-6025 3925);
WIRE 17 -1 (-5825 4775)(-5825 4675);
WIRE 17 -1 (-5825 4675)(-5825 4575);
WIRE 17 -1 (-5825 4575)(-5825 4475);
WIRE 17 -1 (-5825 4375)(-5825 4475);
WIRE 17 -1 (-5825 4275)(-5825 4375);
WIRE 17 -1 (-5825 4175)(-5825 4275);
WIRE 17 -1 (-5825 4175)(-5825 4075);
WIRE 17 -1 (-5825 4075)(-5825 3975);
WIRE 17 -1 (-6025 3725)(-6025 3775);
WIRE 17 -1 (-6025 3675)(-6025 3725);
WIRE 17 -1 (-6025 3775)(-6525 3775);
FORCEPROP 2 LAST SIG_NAME M_H_CPU1_SA_CA<6:0>
J 0
(-6525 3785);
DISPLAY 0.489362 (-6525 3785);
WIRE 17 -1 (-6025 3325)(-6025 3375);
WIRE 17 -1 (-6025 3275)(-6025 3325);
WIRE 17 -1 (-6025 3375)(-6525 3375);
FORCEPROP 2 LAST SIG_NAME M_H_CPU1_SB_CA<6:0>
J 0
(-6525 3385);
DISPLAY 0.489362 (-6525 3385);
WIRE 17 -1 (-6025 3625)(-6025 3675);
WIRE 17 -1 (-6025 3225)(-6025 3275);
WIRE 17 -1 (-6025 3575)(-6025 3625);
WIRE 17 -1 (-6025 3525)(-6025 3575);
WIRE 17 -1 (-6025 3475)(-6025 3525);
WIRE 17 -1 (-6025 3175)(-6025 3225);
WIRE 17 -1 (-6025 3125)(-6025 3175);
WIRE 17 -1 (-6025 3075)(-6025 3125);
WIRE 17 -1 (-6025 5875)(-6625 5875);
WIRE 17 -1 (-6025 4825)(-6625 4825);
WIRE 16 -1 (-7475 2050)(-6750 2050);
FORCEPROP 2 LAST SIG_NAME M_H_CPU1_ALERT_N
J 0
(-7435 2060);
DISPLAY 0.489362 (-7435 2060);
WIRE 16 -1 (-6550 2050)(-5425 2050);
FORCEPROP 2 LAST SIG_NAME M_H_CPU1_ALERT_R_N
J 0
(-6260 2060);
DISPLAY 0.489362 (-6260 2060);
FORCEPROP 2 LASTPROP $XRERR UNIQUE?
J 0
(-6500 2060);
DISPLAY 0.638298 (-6500 2060);
PAINT MONO (-6500 2060);
DISPLAY INVISIBLE (-6500 2060);
WIRE 16 -1 (-6525 1100)(-5425 1100);
FORCEPROP 2 LAST SIG_NAME TP_M_H_CPU1_SA_TEST39H
J 0
(-6510 1110);
DISPLAY 0.489362 (-6510 1110);
FORCEPROP 2 LASTPROP $XRERR UNIQUE?
J 0
(-6765 1100);
DISPLAY 0.638298 (-6765 1100);
PAINT MONO (-6765 1100);
DISPLAY INVISIBLE (-6765 1100);
WIRE 16 -1 (-6525 2850)(-5425 2850);
FORCEPROP 2 LAST SIG_NAME M_H_CPU1_CLK_DN<0>
J 0
(-6525 2860);
DISPLAY 0.489362 (-6525 2860);
WIRE 16 -1 (-6525 2900)(-5425 2900);
FORCEPROP 2 LAST SIG_NAME M_H_CPU1_CLK_DP<0>
J 0
(-6525 2910);
DISPLAY 0.489362 (-6525 2910);
WIRE 16 -1 (-6525 2750)(-5425 2750);
FORCEPROP 2 LAST SIG_NAME M_H_CPU1_SA_CS_N<0>
J 0
(-6525 2760);
DISPLAY 0.489362 (-6525 2760);
WIRE 16 -1 (-6525 2700)(-5425 2700);
FORCEPROP 2 LAST SIG_NAME M_H_CPU1_SA_CS_N<1>
J 0
(-6525 2710);
DISPLAY 0.489362 (-6525 2710);
WIRE 16 -1 (-6525 2600)(-5425 2600);
FORCEPROP 2 LAST SIG_NAME M_H_CPU1_SA_RSP<0>
J 0
(-6525 2610);
DISPLAY 0.489362 (-6525 2610);
WIRE 16 -1 (-6525 2500)(-5425 2500);
FORCEPROP 2 LAST SIG_NAME M_H_CPU1_SA_PAR
J 0
(-6525 2510);
DISPLAY 0.489362 (-6525 2510);
WIRE 16 -1 (-6525 2350)(-5425 2350);
FORCEPROP 2 LAST SIG_NAME M_H_CPU1_SB_CS_N<1>
J 0
(-6525 2360);
DISPLAY 0.489362 (-6525 2360);
WIRE 16 -1 (-6525 2400)(-5425 2400);
FORCEPROP 2 LAST SIG_NAME M_H_CPU1_SB_CS_N<0>
J 0
(-6525 2410);
DISPLAY 0.489362 (-6525 2410);
WIRE 16 -1 (-6525 2250)(-5425 2250);
FORCEPROP 2 LAST SIG_NAME M_H_CPU1_SB_RSP<0>
J 0
(-6525 2260);
DISPLAY 0.489362 (-6525 2260);
WIRE 16 -1 (-6525 2150)(-5425 2150);
FORCEPROP 2 LAST SIG_NAME M_H_CPU1_SB_PAR
J 0
(-6525 2160);
DISPLAY 0.489362 (-6525 2160);
WIRE 16 -1 (-6525 1950)(-5425 1950);
FORCEPROP 2 LAST SIG_NAME M_H_CPU1_RESET_N
J 0
(-6525 1960);
DISPLAY 0.489362 (-6525 1960);
WIRE 16 -1 (-5925 3050)(-5425 3050);
WIRE 16 -1 (-5725 3950)(-5425 3950);
WIRE 16 -1 (-5725 4050)(-5425 4050);
WIRE 16 -1 (-5925 3900)(-5425 3900);
WIRE 16 -1 (-5925 4000)(-5425 4000);
WIRE 16 -1 (-5925 3450)(-5425 3450);
WIRE 16 -1 (-5925 3100)(-5425 3100);
WIRE 16 -1 (-5925 3500)(-5425 3500);
WIRE 16 -1 (-5925 3150)(-5425 3150);
WIRE 16 -1 (-5925 3550)(-5425 3550);
WIRE 16 -1 (-5925 3200)(-5425 3200);
WIRE 16 -1 (-5925 3600)(-5425 3600);
WIRE 16 -1 (-5925 3250)(-5425 3250);
WIRE 16 -1 (-5925 3650)(-5425 3650);
WIRE 16 -1 (-5925 3300)(-5425 3300);
WIRE 16 -1 (-5925 3700)(-5425 3700);
WIRE 16 -1 (-5925 3350)(-5425 3350);
WIRE 16 -1 (-5925 3750)(-5425 3750);
WIRE 16 -1 (-5725 4150)(-5425 4150);
WIRE 16 -1 (-5725 4250)(-5425 4250);
WIRE 16 -1 (-5725 4350)(-5425 4350);
WIRE 16 -1 (-5725 4450)(-5425 4450);
WIRE 16 -1 (-5725 5000)(-5425 5000);
WIRE 16 -1 (-5725 4550)(-5425 4550);
WIRE 16 -1 (-5925 4100)(-5425 4100);
WIRE 16 -1 (-5725 5100)(-5425 5100);
WIRE 16 -1 (-5725 4650)(-5425 4650);
WIRE 16 -1 (-5925 4200)(-5425 4200);
WIRE 16 -1 (-5725 4750)(-5425 4750);
WIRE 16 -1 (-5925 4300)(-5425 4300);
WIRE 16 -1 (-5725 4850)(-5425 4850);
WIRE 16 -1 (-5925 4400)(-5425 4400);
WIRE 16 -1 (-5925 4950)(-5425 4950);
WIRE 16 -1 (-5925 4500)(-5425 4500);
WIRE 16 -1 (-5925 5050)(-5425 5050);
WIRE 16 -1 (-5925 4600)(-5425 4600);
WIRE 16 -1 (-5925 4700)(-5425 4700);
WIRE 16 -1 (-5925 4800)(-5425 4800);
WIRE 16 -1 (-5925 5750)(-5425 5750);
WIRE 16 -1 (-5925 5850)(-5425 5850);
WIRE 16 -1 (-5725 5200)(-5425 5200);
WIRE 16 -1 (-5725 5300)(-5425 5300);
WIRE 16 -1 (-5725 5400)(-5425 5400);
WIRE 16 -1 (-5725 5500)(-5425 5500);
WIRE 16 -1 (-5725 5600)(-5425 5600);
WIRE 16 -1 (-5925 5150)(-5425 5150);
WIRE 16 -1 (-5725 5700)(-5425 5700);
WIRE 16 -1 (-5925 5250)(-5425 5250);
WIRE 16 -1 (-5725 5800)(-5425 5800);
WIRE 16 -1 (-5925 5350)(-5425 5350);
WIRE 16 -1 (-5725 5900)(-5425 5900);
WIRE 16 -1 (-5925 5450)(-5425 5450);
WIRE 16 -1 (-5925 5550)(-5425 5550);
WIRE 16 -1 (-5925 5650)(-5425 5650);
WIRE 16 -1 (-3825 1500)(-3400 1500);
WIRE 16 -1 (-3825 1550)(-3400 1550);
WIRE 16 -1 (-3825 1600)(-3400 1600);
WIRE 16 -1 (-3825 1650)(-3400 1650);
WIRE 16 -1 (-3825 1700)(-3400 1700);
WIRE 16 -1 (-3825 1750)(-3400 1750);
WIRE 16 -1 (-3825 1950)(-3400 1950);
WIRE 16 -1 (-3825 1800)(-3400 1800);
WIRE 16 -1 (-3825 2000)(-3400 2000);
WIRE 16 -1 (-3825 1850)(-3400 1850);
WIRE 16 -1 (-3825 2050)(-3400 2050);
WIRE 16 -1 (-3825 2450)(-3400 2450);
WIRE 16 -1 (-3825 2100)(-3400 2100);
WIRE 16 -1 (-3825 2150)(-3400 2150);
WIRE 16 -1 (-3825 2200)(-3400 2200);
WIRE 16 -1 (-3825 2250)(-3400 2250);
WIRE 16 -1 (-3825 2300)(-3400 2300);
WIRE 16 -1 (-3825 3050)(-3400 3050);
WIRE 16 -1 (-3825 2500)(-3400 2500);
WIRE 16 -1 (-3825 2550)(-3400 2550);
WIRE 16 -1 (-3825 2600)(-3400 2600);
WIRE 16 -1 (-3825 2650)(-3400 2650);
WIRE 16 -1 (-3825 2700)(-3400 2700);
WIRE 16 -1 (-3825 2750)(-3400 2750);
WIRE 16 -1 (-3825 2850)(-3400 2850);
WIRE 16 -1 (-3825 2900)(-3400 2900);
WIRE 16 -1 (-3825 2950)(-3400 2950);
WIRE 16 -1 (-3825 3000)(-3400 3000);
WIRE 16 -1 (-3825 2400)(-3400 2400);
WIRE 16 -1 (-3825 3600)(-3400 3600);
WIRE 16 -1 (-3825 3650)(-3400 3650);
WIRE 16 -1 (-3825 3750)(-3400 3750);
WIRE 16 -1 (-3825 3800)(-3400 3800);
WIRE 16 -1 (-3825 3850)(-3400 3850);
WIRE 16 -1 (-3825 3900)(-3400 3900);
WIRE 16 -1 (-3825 3100)(-3400 3100);
WIRE 16 -1 (-3825 3950)(-3400 3950);
WIRE 16 -1 (-3825 3150)(-3400 3150);
WIRE 16 -1 (-3825 4000)(-3400 4000);
WIRE 16 -1 (-3825 3200)(-3400 3200);
WIRE 16 -1 (-3825 4050)(-3400 4050);
WIRE 16 -1 (-3825 3300)(-3400 3300);
WIRE 16 -1 (-3825 3350)(-3400 3350);
WIRE 16 -1 (-3825 3400)(-3400 3400);
WIRE 16 -1 (-3825 3450)(-3400 3450);
WIRE 16 -1 (-3825 3500)(-3400 3500);
WIRE 16 -1 (-3825 3550)(-3400 3550);
WIRE 16 -1 (-3825 4500)(-3400 4500);
WIRE 16 -1 (-3825 4550)(-3400 4550);
WIRE 16 -1 (-3825 4650)(-3400 4650);
WIRE 16 -1 (-3825 4700)(-3400 4700);
WIRE 16 -1 (-3825 4750)(-3400 4750);
WIRE 16 -1 (-3825 4800)(-3400 4800);
WIRE 16 -1 (-3825 4200)(-3400 4200);
WIRE 16 -1 (-3825 4250)(-3400 4250);
WIRE 16 -1 (-3825 4100)(-3400 4100);
WIRE 16 -1 (-3825 4850)(-3400 4850);
WIRE 16 -1 (-3825 4900)(-3400 4900);
WIRE 16 -1 (-3825 4300)(-3400 4300);
WIRE 16 -1 (-3825 4950)(-3400 4950);
WIRE 16 -1 (-3825 4350)(-3400 4350);
WIRE 16 -1 (-3825 5000)(-3400 5000);
WIRE 16 -1 (-3825 4400)(-3400 4400);
WIRE 16 -1 (-3825 5100)(-3400 5100);
WIRE 16 -1 (-3825 4450)(-3400 4450);
WIRE 16 -1 (-3825 5150)(-3400 5150);
WIRE 16 -1 (-3825 5200)(-3400 5200);
WIRE 16 -1 (-3825 5400)(-3400 5400);
WIRE 16 -1 (-3825 5250)(-3400 5250);
WIRE 16 -1 (-3825 5450)(-3400 5450);
WIRE 16 -1 (-3825 5300)(-3400 5300);
WIRE 16 -1 (-3825 5550)(-3400 5550);
WIRE 16 -1 (-3825 5350)(-3400 5350);
WIRE 16 -1 (-3825 5600)(-3400 5600);
WIRE 16 -1 (-3825 5650)(-3400 5650);
WIRE 16 -1 (-3825 5700)(-3400 5700);
WIRE 16 -1 (-3825 5750)(-3400 5750);
WIRE 16 -1 (-3825 5800)(-3400 5800);
WIRE 16 -1 (-3825 5850)(-3400 5850);
WIRE 16 -1 (-3825 5900)(-3400 5900);
QUIT
